FILE_TYPE = MACRO_DRAWING;
SET COLOR_WIRE YELLOW;
SET COLOR_PROP ORANGE;
SET COLOR_DOT WHITE;
SET COLOR_ARC YELLOW;
SET COLOR_BODY GREEN;
SET COLOR_NOTE PURPLE;
SET PROP_DISPLAY VALUE;
SET PAGE_NUMBER P88;
FORCEADD UNIVERSAL_GND..1
(-1675 -325);
FORCEPROP 3 LASTPIN (-1675 -275) SIG_NAME GND\g
J 0
(-1665 -265);
DISPLAY 0.659574 (-1665 -265);
PAINT MONO (-1665 -265);
DISPLAY INVISIBLE (-1665 -265);
FORCEPROP 2 LAST CDS_LIB logical_power
J 0
(-1675 -325);
PAINT MONO (-1675 -325);
DISPLAY INVISIBLE (-1675 -325);
FORCEPROP 1 LAST HDL_POWER GND
J 1
(-1650 -400);
DISPLAY 0.872340 (-1650 -400);
PAINT GREEN (-1650 -400);
DISPLAY INVISIBLE (-1650 -400);
FORCEPROP 1 LAST PATH I1
J 0
(-1600 -325);
DISPLAY 0.872340 (-1600 -325);
PAINT AQUA (-1600 -325);
DISPLAY INVISIBLE (-1600 -325);
FORCEADD OFFPAGE..1
(-2825 1800);
FORCEPROP 2 LAST $XR3 89 
J 0
(-3077 1764);
DISPLAY 0.638298 (-3077 1764);
PAINT MONO (-3077 1764);
FORCEPROP 2 LAST $XR2 87 
J 0
(-3257 1800);
DISPLAY 0.638298 (-3257 1800);
PAINT MONO (-3257 1800);
FORCEPROP 2 LAST $XR1 86 
J 0
(-3167 1800);
DISPLAY 0.638298 (-3167 1800);
PAINT MONO (-3167 1800);
FORCEPROP 2 LAST $XR0 129 
J 0
(-3077 1800);
DISPLAY 0.638298 (-3077 1800);
PAINT MONO (-3077 1800);
FORCEPROP 2 LAST CDS_LIB standard
J 0
(-2825 1800);
PAINT MONO (-2825 1800);
DISPLAY INVISIBLE (-2825 1800);
FORCEPROP 1 LAST OFFPAGE TRUE
J 0
(-2500 1675);
DISPLAY 0.872340 (-2500 1675);
DISPLAY INVISIBLE (-2500 1675);
FORCEPROP 1 LAST COMMENT_BODY TRUE
J 0
(-2700 1700);
DISPLAY 0.872340 (-2700 1700);
PAINT GREEN (-2700 1700);
DISPLAY INVISIBLE (-2700 1700);
FORCEPROP 2 LAST PATH I10
J 0
(-2775 1875);
DISPLAY 1.021277 (-2775 1875);
DISPLAY INVISIBLE (-2775 1875);
FORCEADD TAP..1
(-250 3350);
FORCEPROP 3 LASTPIN (-300 3350) SIG_NAME M_D_CPU0_SA_DQ<17>
J 0
(-290 3360);
DISPLAY 0.659574 (-290 3360);
PAINT MONO (-290 3360);
DISPLAY INVISIBLE (-290 3360);
FORCEPROP 1 LASTPIN (-300 3350) BN 17
J 0
(-312 3358);
DISPLAY 0.680851 (-312 3358);
PAINT GREEN (-312 3358);
FORCEPROP 2 LAST CDS_LIB standard
J 0
(-250 3350);
PAINT MONO (-250 3350);
DISPLAY INVISIBLE (-250 3350);
FORCEPROP 1 LAST BODY_TYPE PLUMBING
J 0
(-250 3400);
DISPLAY 0.872340 (-250 3400);
PAINT GREEN (-250 3400);
DISPLAY INVISIBLE (-250 3400);
FORCEPROP 1 LAST HDL_TAP TRUE
J 0
(75 3225);
DISPLAY 0.872340 (75 3225);
DISPLAY INVISIBLE (75 3225);
FORCEPROP 1 LAST PATH I100
J 0
(-252 3350);
DISPLAY 0.872340 (-252 3350);
PAINT GREEN (-252 3350);
DISPLAY INVISIBLE (-252 3350);
FORCEADD TAP..1
(-250 3300);
FORCEPROP 3 LASTPIN (-300 3300) SIG_NAME M_D_CPU0_SA_DQ<16>
J 0
(-290 3310);
DISPLAY 0.659574 (-290 3310);
PAINT MONO (-290 3310);
DISPLAY INVISIBLE (-290 3310);
FORCEPROP 1 LASTPIN (-300 3300) BN 16
J 0
(-312 3308);
DISPLAY 0.680851 (-312 3308);
PAINT GREEN (-312 3308);
FORCEPROP 2 LAST CDS_LIB standard
J 0
(-250 3300);
PAINT MONO (-250 3300);
DISPLAY INVISIBLE (-250 3300);
FORCEPROP 1 LAST BODY_TYPE PLUMBING
J 0
(-250 3350);
DISPLAY 0.872340 (-250 3350);
PAINT GREEN (-250 3350);
DISPLAY INVISIBLE (-250 3350);
FORCEPROP 1 LAST HDL_TAP TRUE
J 0
(75 3175);
DISPLAY 0.872340 (75 3175);
DISPLAY INVISIBLE (75 3175);
FORCEPROP 1 LAST PATH I101
J 0
(-252 3300);
DISPLAY 0.872340 (-252 3300);
PAINT GREEN (-252 3300);
DISPLAY INVISIBLE (-252 3300);
FORCEADD TAP..1
(-250 3450);
FORCEPROP 3 LASTPIN (-300 3450) SIG_NAME M_D_CPU0_SA_DQ<19>
J 0
(-290 3460);
DISPLAY 0.659574 (-290 3460);
PAINT MONO (-290 3460);
DISPLAY INVISIBLE (-290 3460);
FORCEPROP 1 LASTPIN (-300 3450) BN 19
J 0
(-312 3458);
DISPLAY 0.680851 (-312 3458);
PAINT GREEN (-312 3458);
FORCEPROP 2 LAST CDS_LIB standard
J 0
(-250 3450);
PAINT MONO (-250 3450);
DISPLAY INVISIBLE (-250 3450);
FORCEPROP 1 LAST BODY_TYPE PLUMBING
J 0
(-250 3500);
DISPLAY 0.872340 (-250 3500);
PAINT GREEN (-250 3500);
DISPLAY INVISIBLE (-250 3500);
FORCEPROP 1 LAST HDL_TAP TRUE
J 0
(75 3325);
DISPLAY 0.872340 (75 3325);
DISPLAY INVISIBLE (75 3325);
FORCEPROP 1 LAST PATH I102
J 0
(-252 3450);
DISPLAY 0.872340 (-252 3450);
PAINT GREEN (-252 3450);
DISPLAY INVISIBLE (-252 3450);
FORCEADD TAP..1
(-250 3400);
FORCEPROP 3 LASTPIN (-300 3400) SIG_NAME M_D_CPU0_SA_DQ<18>
J 0
(-290 3410);
DISPLAY 0.659574 (-290 3410);
PAINT MONO (-290 3410);
DISPLAY INVISIBLE (-290 3410);
FORCEPROP 1 LASTPIN (-300 3400) BN 18
J 0
(-312 3408);
DISPLAY 0.680851 (-312 3408);
PAINT GREEN (-312 3408);
FORCEPROP 2 LAST CDS_LIB standard
J 0
(-250 3400);
PAINT MONO (-250 3400);
DISPLAY INVISIBLE (-250 3400);
FORCEPROP 1 LAST BODY_TYPE PLUMBING
J 0
(-250 3450);
DISPLAY 0.872340 (-250 3450);
PAINT GREEN (-250 3450);
DISPLAY INVISIBLE (-250 3450);
FORCEPROP 1 LAST HDL_TAP TRUE
J 0
(75 3275);
DISPLAY 0.872340 (75 3275);
DISPLAY INVISIBLE (75 3275);
FORCEPROP 1 LAST PATH I103
J 0
(-252 3400);
DISPLAY 0.872340 (-252 3400);
PAINT GREEN (-252 3400);
DISPLAY INVISIBLE (-252 3400);
FORCEADD TAP..1
(-250 3500);
FORCEPROP 3 LASTPIN (-300 3500) SIG_NAME M_D_CPU0_SA_DQ<20>
J 0
(-290 3510);
DISPLAY 0.659574 (-290 3510);
PAINT MONO (-290 3510);
DISPLAY INVISIBLE (-290 3510);
FORCEPROP 1 LASTPIN (-300 3500) BN 20
J 0
(-312 3508);
DISPLAY 0.680851 (-312 3508);
PAINT GREEN (-312 3508);
FORCEPROP 2 LAST CDS_LIB standard
J 0
(-250 3500);
PAINT MONO (-250 3500);
DISPLAY INVISIBLE (-250 3500);
FORCEPROP 1 LAST BODY_TYPE PLUMBING
J 0
(-250 3550);
DISPLAY 0.872340 (-250 3550);
PAINT GREEN (-250 3550);
DISPLAY INVISIBLE (-250 3550);
FORCEPROP 1 LAST HDL_TAP TRUE
J 0
(75 3375);
DISPLAY 0.872340 (75 3375);
DISPLAY INVISIBLE (75 3375);
FORCEPROP 1 LAST PATH I104
J 0
(-252 3500);
DISPLAY 0.872340 (-252 3500);
PAINT GREEN (-252 3500);
DISPLAY INVISIBLE (-252 3500);
FORCEADD TAP..1
(-250 3600);
FORCEPROP 3 LASTPIN (-300 3600) SIG_NAME M_D_CPU0_SA_DQ<22>
J 0
(-290 3610);
DISPLAY 0.659574 (-290 3610);
PAINT MONO (-290 3610);
DISPLAY INVISIBLE (-290 3610);
FORCEPROP 1 LASTPIN (-300 3600) BN 22
J 0
(-312 3608);
DISPLAY 0.680851 (-312 3608);
PAINT GREEN (-312 3608);
FORCEPROP 2 LAST CDS_LIB standard
J 0
(-250 3600);
DISPLAY INVISIBLE (-250 3600);
FORCEPROP 1 LAST BODY_TYPE PLUMBING
J 0
(-250 3650);
DISPLAY 0.872340 (-250 3650);
PAINT GREEN (-250 3650);
DISPLAY INVISIBLE (-250 3650);
FORCEPROP 1 LAST HDL_TAP TRUE
J 0
(75 3475);
DISPLAY 0.872340 (75 3475);
DISPLAY INVISIBLE (75 3475);
FORCEPROP 1 LAST PATH I105
J 0
(-252 3600);
DISPLAY 0.872340 (-252 3600);
PAINT GREEN (-252 3600);
DISPLAY INVISIBLE (-252 3600);
FORCEADD TAP..1
(-250 3550);
FORCEPROP 3 LASTPIN (-300 3550) SIG_NAME M_D_CPU0_SA_DQ<21>
J 0
(-290 3560);
DISPLAY 0.659574 (-290 3560);
PAINT MONO (-290 3560);
DISPLAY INVISIBLE (-290 3560);
FORCEPROP 1 LASTPIN (-300 3550) BN 21
J 0
(-312 3558);
DISPLAY 0.680851 (-312 3558);
PAINT GREEN (-312 3558);
FORCEPROP 2 LAST CDS_LIB standard
J 0
(-250 3550);
PAINT MONO (-250 3550);
DISPLAY INVISIBLE (-250 3550);
FORCEPROP 1 LAST BODY_TYPE PLUMBING
J 0
(-250 3600);
DISPLAY 0.872340 (-250 3600);
PAINT GREEN (-250 3600);
DISPLAY INVISIBLE (-250 3600);
FORCEPROP 1 LAST HDL_TAP TRUE
J 0
(75 3425);
DISPLAY 0.872340 (75 3425);
DISPLAY INVISIBLE (75 3425);
FORCEPROP 1 LAST PATH I106
J 0
(-252 3550);
DISPLAY 0.872340 (-252 3550);
PAINT GREEN (-252 3550);
DISPLAY INVISIBLE (-252 3550);
FORCEADD TAP..1
(-250 3650);
FORCEPROP 3 LASTPIN (-300 3650) SIG_NAME M_D_CPU0_SA_DQ<23>
J 0
(-290 3660);
DISPLAY 0.659574 (-290 3660);
PAINT MONO (-290 3660);
DISPLAY INVISIBLE (-290 3660);
FORCEPROP 1 LASTPIN (-300 3650) BN 23
J 0
(-312 3658);
DISPLAY 0.680851 (-312 3658);
PAINT GREEN (-312 3658);
FORCEPROP 2 LAST CDS_LIB standard
J 0
(-250 3650);
DISPLAY INVISIBLE (-250 3650);
FORCEPROP 1 LAST BODY_TYPE PLUMBING
J 0
(-250 3700);
DISPLAY 0.872340 (-250 3700);
PAINT GREEN (-250 3700);
DISPLAY INVISIBLE (-250 3700);
FORCEPROP 1 LAST HDL_TAP TRUE
J 0
(75 3525);
DISPLAY 0.872340 (75 3525);
DISPLAY INVISIBLE (75 3525);
FORCEPROP 1 LAST PATH I107
J 0
(-252 3650);
DISPLAY 0.872340 (-252 3650);
PAINT GREEN (-252 3650);
DISPLAY INVISIBLE (-252 3650);
FORCEADD TAP..1
(-250 3700);
FORCEPROP 3 LASTPIN (-300 3700) SIG_NAME M_D_CPU0_SA_DQ<24>
J 0
(-290 3710);
DISPLAY 0.659574 (-290 3710);
PAINT MONO (-290 3710);
DISPLAY INVISIBLE (-290 3710);
FORCEPROP 1 LASTPIN (-300 3700) BN 24
J 0
(-312 3708);
DISPLAY 0.680851 (-312 3708);
PAINT GREEN (-312 3708);
FORCEPROP 2 LAST CDS_LIB standard
J 0
(-250 3700);
DISPLAY INVISIBLE (-250 3700);
FORCEPROP 1 LAST BODY_TYPE PLUMBING
J 0
(-250 3750);
DISPLAY 0.872340 (-250 3750);
PAINT GREEN (-250 3750);
DISPLAY INVISIBLE (-250 3750);
FORCEPROP 1 LAST HDL_TAP TRUE
J 0
(75 3575);
DISPLAY 0.872340 (75 3575);
DISPLAY INVISIBLE (75 3575);
FORCEPROP 1 LAST PATH I108
J 0
(-252 3700);
DISPLAY 0.872340 (-252 3700);
PAINT GREEN (-252 3700);
DISPLAY INVISIBLE (-252 3700);
FORCEADD TAP..1
(-250 3800);
FORCEPROP 3 LASTPIN (-300 3800) SIG_NAME M_D_CPU0_SA_DQ<26>
J 0
(-290 3810);
DISPLAY 0.659574 (-290 3810);
PAINT MONO (-290 3810);
DISPLAY INVISIBLE (-290 3810);
FORCEPROP 1 LASTPIN (-300 3800) BN 26
J 0
(-312 3808);
DISPLAY 0.680851 (-312 3808);
PAINT GREEN (-312 3808);
FORCEPROP 2 LAST CDS_LIB standard
J 0
(-250 3800);
DISPLAY INVISIBLE (-250 3800);
FORCEPROP 1 LAST BODY_TYPE PLUMBING
J 0
(-250 3850);
DISPLAY 0.872340 (-250 3850);
PAINT GREEN (-250 3850);
DISPLAY INVISIBLE (-250 3850);
FORCEPROP 1 LAST HDL_TAP TRUE
J 0
(75 3675);
DISPLAY 0.872340 (75 3675);
DISPLAY INVISIBLE (75 3675);
FORCEPROP 1 LAST PATH I109
J 0
(-252 3800);
DISPLAY 0.872340 (-252 3800);
PAINT GREEN (-252 3800);
DISPLAY INVISIBLE (-252 3800);
FORCEADD VCC_CORE..1
(-2725 1925);
FORCEPROP 3 LASTPIN (-2725 1875) SIG_NAME P3V3_AUX\g
J 0
(-2715 1885);
DISPLAY 0.659574 (-2715 1885);
PAINT MONO (-2715 1885);
DISPLAY INVISIBLE (-2715 1885);
FORCEPROP 1 LAST HDL_POWER P3V3_AUX
J 1
(-2725 1975);
DISPLAY 1.148936 (-2725 1975);
PAINT GREEN (-2725 1975);
FORCEPROP 2 LAST CDS_LIB logical_power
J 0
(-2725 1925);
PAINT MONO (-2725 1925);
DISPLAY INVISIBLE (-2725 1925);
FORCEPROP 1 LAST PATH I11
J 0
(-2675 1950);
DISPLAY 0.872340 (-2675 1950);
PAINT AQUA (-2675 1950);
DISPLAY INVISIBLE (-2675 1950);
FORCEADD TAP..1
(-250 3750);
FORCEPROP 3 LASTPIN (-300 3750) SIG_NAME M_D_CPU0_SA_DQ<25>
J 0
(-290 3760);
DISPLAY 0.659574 (-290 3760);
PAINT MONO (-290 3760);
DISPLAY INVISIBLE (-290 3760);
FORCEPROP 1 LASTPIN (-300 3750) BN 25
J 0
(-312 3758);
DISPLAY 0.680851 (-312 3758);
PAINT GREEN (-312 3758);
FORCEPROP 2 LAST CDS_LIB standard
J 0
(-250 3750);
DISPLAY INVISIBLE (-250 3750);
FORCEPROP 1 LAST BODY_TYPE PLUMBING
J 0
(-250 3800);
DISPLAY 0.872340 (-250 3800);
PAINT GREEN (-250 3800);
DISPLAY INVISIBLE (-250 3800);
FORCEPROP 1 LAST HDL_TAP TRUE
J 0
(75 3625);
DISPLAY 0.872340 (75 3625);
DISPLAY INVISIBLE (75 3625);
FORCEPROP 1 LAST PATH I110
J 0
(-252 3750);
DISPLAY 0.872340 (-252 3750);
PAINT GREEN (-252 3750);
DISPLAY INVISIBLE (-252 3750);
FORCEADD TAP..1
(-250 3850);
FORCEPROP 3 LASTPIN (-300 3850) SIG_NAME M_D_CPU0_SA_DQ<27>
J 0
(-290 3860);
DISPLAY 0.659574 (-290 3860);
PAINT MONO (-290 3860);
DISPLAY INVISIBLE (-290 3860);
FORCEPROP 1 LASTPIN (-300 3850) BN 27
J 0
(-312 3858);
DISPLAY 0.680851 (-312 3858);
PAINT GREEN (-312 3858);
FORCEPROP 2 LAST CDS_LIB standard
J 0
(-250 3850);
DISPLAY INVISIBLE (-250 3850);
FORCEPROP 1 LAST BODY_TYPE PLUMBING
J 0
(-250 3900);
DISPLAY 0.872340 (-250 3900);
PAINT GREEN (-250 3900);
DISPLAY INVISIBLE (-250 3900);
FORCEPROP 1 LAST HDL_TAP TRUE
J 0
(75 3725);
DISPLAY 0.872340 (75 3725);
DISPLAY INVISIBLE (75 3725);
FORCEPROP 1 LAST PATH I111
J 0
(-252 3850);
DISPLAY 0.872340 (-252 3850);
PAINT GREEN (-252 3850);
DISPLAY INVISIBLE (-252 3850);
FORCEADD TAP..1
(-250 3950);
FORCEPROP 3 LASTPIN (-300 3950) SIG_NAME M_D_CPU0_SA_DQ<29>
J 0
(-290 3960);
DISPLAY 0.659574 (-290 3960);
PAINT MONO (-290 3960);
DISPLAY INVISIBLE (-290 3960);
FORCEPROP 1 LASTPIN (-300 3950) BN 29
J 0
(-312 3958);
DISPLAY 0.680851 (-312 3958);
PAINT GREEN (-312 3958);
FORCEPROP 2 LAST CDS_LIB standard
J 0
(-250 3950);
DISPLAY INVISIBLE (-250 3950);
FORCEPROP 1 LAST BODY_TYPE PLUMBING
J 0
(-250 4000);
DISPLAY 0.872340 (-250 4000);
PAINT GREEN (-250 4000);
DISPLAY INVISIBLE (-250 4000);
FORCEPROP 1 LAST HDL_TAP TRUE
J 0
(75 3825);
DISPLAY 0.872340 (75 3825);
DISPLAY INVISIBLE (75 3825);
FORCEPROP 1 LAST PATH I112
J 0
(-252 3950);
DISPLAY 0.872340 (-252 3950);
PAINT GREEN (-252 3950);
DISPLAY INVISIBLE (-252 3950);
FORCEADD TAP..1
(-250 3900);
FORCEPROP 3 LASTPIN (-300 3900) SIG_NAME M_D_CPU0_SA_DQ<28>
J 0
(-290 3910);
DISPLAY 0.659574 (-290 3910);
PAINT MONO (-290 3910);
DISPLAY INVISIBLE (-290 3910);
FORCEPROP 1 LASTPIN (-300 3900) BN 28
J 0
(-312 3908);
DISPLAY 0.680851 (-312 3908);
PAINT GREEN (-312 3908);
FORCEPROP 2 LAST CDS_LIB standard
J 0
(-250 3900);
DISPLAY INVISIBLE (-250 3900);
FORCEPROP 1 LAST BODY_TYPE PLUMBING
J 0
(-250 3950);
DISPLAY 0.872340 (-250 3950);
PAINT GREEN (-250 3950);
DISPLAY INVISIBLE (-250 3950);
FORCEPROP 1 LAST HDL_TAP TRUE
J 0
(75 3775);
DISPLAY 0.872340 (75 3775);
DISPLAY INVISIBLE (75 3775);
FORCEPROP 1 LAST PATH I113
J 0
(-252 3900);
DISPLAY 0.872340 (-252 3900);
PAINT GREEN (-252 3900);
DISPLAY INVISIBLE (-252 3900);
FORCEADD OFFPAGE..3
(575 2425);
FORCEPROP 2 LAST $XR1 89 
J 0
(879 2425);
DISPLAY 0.638298 (879 2425);
PAINT MONO (879 2425);
FORCEPROP 2 LAST $XR0 23 
J 0
(789 2425);
DISPLAY 0.638298 (789 2425);
PAINT MONO (789 2425);
FORCEPROP 2 LAST CDS_LIB standard
J 2
(575 2425);
DISPLAY INVISIBLE (575 2425);
FORCEPROP 1 LAST OFFPAGE TRUE
J 0
(900 2300);
DISPLAY 0.872340 (900 2300);
DISPLAY INVISIBLE (900 2300);
FORCEPROP 1 LAST COMMENT_BODY TRUE
J 0
(525 2325);
DISPLAY 0.872340 (525 2325);
PAINT GREEN (525 2325);
DISPLAY INVISIBLE (525 2325);
FORCEPROP 2 LAST PATH I114
J 0
(775 2500);
DISPLAY 1.021277 (775 2500);
DISPLAY INVISIBLE (775 2500);
FORCEADD OFFPAGE..1
(-2825 4075);
FORCEPROP 2 LAST $XR1 89 
J 0
(-3136 4075);
DISPLAY 0.638298 (-3136 4075);
PAINT MONO (-3136 4075);
FORCEPROP 2 LAST $XR0 23 
J 0
(-3046 4075);
DISPLAY 0.638298 (-3046 4075);
PAINT MONO (-3046 4075);
FORCEPROP 2 LAST CDS_LIB standard
J 0
(-2825 4075);
PAINT MONO (-2825 4075);
DISPLAY INVISIBLE (-2825 4075);
FORCEPROP 1 LAST OFFPAGE TRUE
J 0
(-2500 3950);
DISPLAY 0.872340 (-2500 3950);
DISPLAY INVISIBLE (-2500 3950);
FORCEPROP 1 LAST COMMENT_BODY TRUE
J 0
(-2700 3975);
DISPLAY 0.872340 (-2700 3975);
PAINT GREEN (-2700 3975);
DISPLAY INVISIBLE (-2700 3975);
FORCEPROP 2 LAST PATH I115
J 0
(-2775 4150);
DISPLAY 1.021277 (-2775 4150);
DISPLAY INVISIBLE (-2775 4150);
FORCEADD TAP..1
R 2
(-1900 4050);
FORCEPROP 3 LASTPIN (-1850 4050) SIG_NAME M_D_CPU0_SA_CA<6>
J 0
(-1840 4060);
DISPLAY 0.659574 (-1840 4060);
PAINT MONO (-1840 4060);
DISPLAY INVISIBLE (-1840 4060);
FORCEPROP 1 LASTPIN (-1850 4050) BN 6
J 2
(-1838 4058);
DISPLAY 0.680851 (-1838 4058);
PAINT GREEN (-1838 4058);
FORCEPROP 2 LAST CDS_LIB standard
J 0
(-1900 4050);
DISPLAY INVISIBLE (-1900 4050);
FORCEPROP 1 LAST BODY_TYPE PLUMBING
J 2
(-1900 4100);
DISPLAY 0.872340 (-1900 4100);
PAINT GREEN (-1900 4100);
DISPLAY INVISIBLE (-1900 4100);
FORCEPROP 1 LAST HDL_TAP TRUE
J 2
(-2225 3925);
DISPLAY 0.872340 (-2225 3925);
DISPLAY INVISIBLE (-2225 3925);
FORCEPROP 1 LAST PATH I116
J 2
(-1898 4050);
DISPLAY 0.872340 (-1898 4050);
PAINT GREEN (-1898 4050);
DISPLAY INVISIBLE (-1898 4050);
FORCEADD TAP..1
R 2
(-1900 4000);
FORCEPROP 3 LASTPIN (-1850 4000) SIG_NAME M_D_CPU0_SA_CA<5>
J 0
(-1840 4010);
DISPLAY 0.659574 (-1840 4010);
PAINT MONO (-1840 4010);
DISPLAY INVISIBLE (-1840 4010);
FORCEPROP 1 LASTPIN (-1850 4000) BN 5
J 2
(-1838 4008);
DISPLAY 0.680851 (-1838 4008);
PAINT GREEN (-1838 4008);
FORCEPROP 2 LAST CDS_LIB standard
J 0
(-1900 4000);
DISPLAY INVISIBLE (-1900 4000);
FORCEPROP 1 LAST BODY_TYPE PLUMBING
J 2
(-1900 4050);
DISPLAY 0.872340 (-1900 4050);
PAINT GREEN (-1900 4050);
DISPLAY INVISIBLE (-1900 4050);
FORCEPROP 1 LAST HDL_TAP TRUE
J 2
(-2225 3875);
DISPLAY 0.872340 (-2225 3875);
DISPLAY INVISIBLE (-2225 3875);
FORCEPROP 1 LAST PATH I117
J 2
(-1898 4000);
DISPLAY 0.872340 (-1898 4000);
PAINT GREEN (-1898 4000);
DISPLAY INVISIBLE (-1898 4000);
FORCEADD TAP..1
(-250 4050);
FORCEPROP 3 LASTPIN (-300 4050) SIG_NAME M_D_CPU0_SA_DQ<31>
J 0
(-290 4060);
DISPLAY 0.659574 (-290 4060);
PAINT MONO (-290 4060);
DISPLAY INVISIBLE (-290 4060);
FORCEPROP 1 LASTPIN (-300 4050) BN 31
J 0
(-312 4058);
DISPLAY 0.680851 (-312 4058);
PAINT GREEN (-312 4058);
FORCEPROP 2 LAST CDS_LIB standard
J 0
(-250 4050);
DISPLAY INVISIBLE (-250 4050);
FORCEPROP 1 LAST BODY_TYPE PLUMBING
J 0
(-250 4100);
DISPLAY 0.872340 (-250 4100);
PAINT GREEN (-250 4100);
DISPLAY INVISIBLE (-250 4100);
FORCEPROP 1 LAST HDL_TAP TRUE
J 0
(75 3925);
DISPLAY 0.872340 (75 3925);
DISPLAY INVISIBLE (75 3925);
FORCEPROP 1 LAST PATH I118
J 0
(-252 4050);
DISPLAY 0.872340 (-252 4050);
PAINT GREEN (-252 4050);
DISPLAY INVISIBLE (-252 4050);
FORCEADD TAP..1
(-250 4000);
FORCEPROP 3 LASTPIN (-300 4000) SIG_NAME M_D_CPU0_SA_DQ<30>
J 0
(-290 4010);
DISPLAY 0.659574 (-290 4010);
PAINT MONO (-290 4010);
DISPLAY INVISIBLE (-290 4010);
FORCEPROP 1 LASTPIN (-300 4000) BN 30
J 0
(-312 4008);
DISPLAY 0.680851 (-312 4008);
PAINT GREEN (-312 4008);
FORCEPROP 2 LAST CDS_LIB standard
J 0
(-250 4000);
DISPLAY INVISIBLE (-250 4000);
FORCEPROP 1 LAST BODY_TYPE PLUMBING
J 0
(-250 4050);
DISPLAY 0.872340 (-250 4050);
PAINT GREEN (-250 4050);
DISPLAY INVISIBLE (-250 4050);
FORCEPROP 1 LAST HDL_TAP TRUE
J 0
(75 3875);
DISPLAY 0.872340 (75 3875);
DISPLAY INVISIBLE (75 3875);
FORCEPROP 1 LAST PATH I119
J 0
(-252 4000);
DISPLAY 0.872340 (-252 4000);
PAINT GREEN (-252 4000);
DISPLAY INVISIBLE (-252 4000);
FORCEADD SCONN288_ADR50017P130CC..1
(-1075 2325);
FORCEPROP 1 LAST PART_NUMBER DFHST8FS461
J 0
(-1520 4347);
DISPLAY 0.723404 (-1520 4347);
PAINT GREEN (-1520 4347);
DISPLAY INVISIBLE (-1520 4347);
FORCEPROP 1 LAST MATERIAL IO
J 0
(-1520 4220);
DISPLAY 0.723404 (-1520 4220);
PAINT GREEN (-1520 4220);
FORCEPROP 2 LAST VALUE SCONN288_ADR50017-P130CC
J 0
(-1525 4450);
DISPLAY 1.021277 (-1525 4450);
FORCEPROP 2 LAST PART_TYPE SMLF
J 0
(-1525 4525);
DISPLAY 1.021277 (-1525 4525);
FORCEPROP 1 LAST $LOCATION J7
J 0
(-1525 4400);
DISPLAY 0.723404 (-1525 4400);
PAINT GREEN (-1525 4400);
FORCEPROP 0 LASTPIN (-1675 1700) $PN 62
J 2
(-1685 1710);
DISPLAY 0.680851 (-1685 1710);
PAINT MONO (-1685 1710);
FORCEPROP 0 LASTPIN (-1675 3750) $PN 66
J 2
(-1685 3760);
DISPLAY 0.680851 (-1685 3760);
PAINT MONO (-1685 3760);
FORCEPROP 0 LASTPIN (-1675 3350) $PN 76
J 2
(-1685 3360);
DISPLAY 0.680851 (-1685 3360);
PAINT MONO (-1685 3360);
FORCEPROP 0 LASTPIN (-1675 3800) $PN 211
J 2
(-1685 3810);
DISPLAY 0.680851 (-1685 3810);
PAINT MONO (-1685 3810);
FORCEPROP 0 LASTPIN (-1675 3400) $PN 221
J 2
(-1685 3410);
DISPLAY 0.680851 (-1685 3410);
PAINT MONO (-1685 3410);
FORCEPROP 0 LASTPIN (-1675 3850) $PN 68
J 2
(-1685 3860);
DISPLAY 0.680851 (-1685 3860);
PAINT MONO (-1685 3860);
FORCEPROP 0 LASTPIN (-1675 3450) $PN 78
J 2
(-1685 3460);
DISPLAY 0.680851 (-1685 3460);
PAINT MONO (-1685 3460);
FORCEPROP 0 LASTPIN (-1675 3900) $PN 213
J 2
(-1685 3910);
DISPLAY 0.680851 (-1685 3910);
PAINT MONO (-1685 3910);
FORCEPROP 0 LASTPIN (-1675 3500) $PN 223
J 2
(-1685 3510);
DISPLAY 0.680851 (-1685 3510);
PAINT MONO (-1685 3510);
FORCEPROP 0 LASTPIN (-1675 3950) $PN 70
J 2
(-1685 3960);
DISPLAY 0.680851 (-1685 3960);
PAINT MONO (-1685 3960);
FORCEPROP 0 LASTPIN (-1675 3550) $PN 80
J 2
(-1685 3560);
DISPLAY 0.680851 (-1685 3560);
PAINT MONO (-1685 3560);
FORCEPROP 0 LASTPIN (-1675 4000) $PN 215
J 2
(-1685 4010);
DISPLAY 0.680851 (-1685 4010);
PAINT MONO (-1685 4010);
FORCEPROP 0 LASTPIN (-1675 3600) $PN 225
J 2
(-1685 3610);
DISPLAY 0.680851 (-1685 3610);
PAINT MONO (-1685 3610);
FORCEPROP 0 LASTPIN (-1675 4050) $PN 72
J 2
(-1685 4060);
DISPLAY 0.680851 (-1685 4060);
PAINT MONO (-1685 4060);
FORCEPROP 0 LASTPIN (-1675 3650) $PN 82
J 2
(-1685 3660);
DISPLAY 0.680851 (-1685 3660);
PAINT MONO (-1685 3660);
FORCEPROP 0 LASTPIN (-1675 2300) $PN 51
J 2
(-1685 2310);
DISPLAY 0.680851 (-1685 2310);
PAINT MONO (-1685 2310);
FORCEPROP 0 LASTPIN (-1675 1850) $PN 96
J 2
(-1685 1860);
DISPLAY 0.680851 (-1685 1860);
PAINT MONO (-1685 1860);
FORCEPROP 0 LASTPIN (-1675 2350) $PN 53
J 2
(-1685 2360);
DISPLAY 0.680851 (-1685 2360);
PAINT MONO (-1685 2360);
FORCEPROP 0 LASTPIN (-1675 1900) $PN 98
J 2
(-1685 1910);
DISPLAY 0.680851 (-1685 1910);
PAINT MONO (-1685 1910);
FORCEPROP 0 LASTPIN (-1675 2400) $PN 196
J 2
(-1685 2410);
DISPLAY 0.680851 (-1685 2410);
PAINT MONO (-1685 2410);
FORCEPROP 0 LASTPIN (-1675 1950) $PN 241
J 2
(-1685 1960);
DISPLAY 0.680851 (-1685 1960);
PAINT MONO (-1685 1960);
FORCEPROP 0 LASTPIN (-1675 2450) $PN 198
J 2
(-1685 2460);
DISPLAY 0.680851 (-1685 2460);
PAINT MONO (-1685 2460);
FORCEPROP 0 LASTPIN (-1675 2000) $PN 243
J 2
(-1685 2010);
DISPLAY 0.680851 (-1685 2010);
PAINT MONO (-1685 2010);
FORCEPROP 0 LASTPIN (-1675 2500) $PN 58
J 2
(-1685 2510);
DISPLAY 0.680851 (-1685 2510);
PAINT MONO (-1685 2510);
FORCEPROP 0 LASTPIN (-1675 2050) $PN 89
J 2
(-1685 2060);
DISPLAY 0.680851 (-1685 2060);
PAINT MONO (-1685 2060);
FORCEPROP 0 LASTPIN (-1675 2550) $PN 60
J 2
(-1685 2560);
DISPLAY 0.680851 (-1685 2560);
PAINT MONO (-1685 2560);
FORCEPROP 0 LASTPIN (-1675 2100) $PN 91
J 2
(-1685 2110);
DISPLAY 0.680851 (-1685 2110);
PAINT MONO (-1685 2110);
FORCEPROP 0 LASTPIN (-1675 2600) $PN 203
J 2
(-1685 2610);
DISPLAY 0.680851 (-1685 2610);
PAINT MONO (-1685 2610);
FORCEPROP 0 LASTPIN (-1675 2150) $PN 234
J 2
(-1685 2160);
DISPLAY 0.680851 (-1685 2160);
PAINT MONO (-1685 2160);
FORCEPROP 0 LASTPIN (-1675 2650) $PN 205
J 2
(-1685 2660);
DISPLAY 0.680851 (-1685 2660);
PAINT MONO (-1685 2660);
FORCEPROP 0 LASTPIN (-1675 2200) $PN 236
J 2
(-1685 2210);
DISPLAY 0.680851 (-1685 2210);
PAINT MONO (-1685 2210);
FORCEPROP 0 LASTPIN (-1675 2750) $PN 218
J 2
(-1685 2760);
DISPLAY 0.680851 (-1685 2760);
PAINT MONO (-1685 2760);
FORCEPROP 0 LASTPIN (-1675 2800) $PN 217
J 2
(-1685 2810);
DISPLAY 0.680851 (-1685 2810);
PAINT MONO (-1685 2810);
FORCEPROP 0 LASTPIN (-1675 3050) $PN 64
J 2
(-1685 3060);
DISPLAY 0.680851 (-1685 3060);
PAINT MONO (-1685 3060);
FORCEPROP 0 LASTPIN (-1675 2900) $PN 84
J 2
(-1685 2910);
DISPLAY 0.680851 (-1685 2910);
PAINT MONO (-1685 2910);
FORCEPROP 0 LASTPIN (-1675 3100) $PN 209
J 2
(-1685 3110);
DISPLAY 0.680851 (-1685 3110);
PAINT MONO (-1685 3110);
FORCEPROP 0 LASTPIN (-1675 2950) $PN 229
J 2
(-1685 2960);
DISPLAY 0.680851 (-1685 2960);
PAINT MONO (-1685 2960);
FORCEPROP 0 LASTPIN (-475 2500) $PN 7
J 0
(-465 2510);
DISPLAY 0.680851 (-465 2510);
PAINT MONO (-465 2510);
FORCEPROP 0 LASTPIN (-475 850) $PN 100
J 0
(-465 860);
DISPLAY 0.680851 (-465 860);
PAINT MONO (-465 860);
FORCEPROP 0 LASTPIN (-475 2550) $PN 9
J 0
(-465 2560);
DISPLAY 0.680851 (-465 2560);
PAINT MONO (-465 2560);
FORCEPROP 0 LASTPIN (-475 900) $PN 102
J 0
(-465 910);
DISPLAY 0.680851 (-465 910);
PAINT MONO (-465 910);
FORCEPROP 0 LASTPIN (-475 2600) $PN 152
J 0
(-465 2610);
DISPLAY 0.680851 (-465 2610);
PAINT MONO (-465 2610);
FORCEPROP 0 LASTPIN (-475 950) $PN 245
J 0
(-465 960);
DISPLAY 0.680851 (-465 960);
PAINT MONO (-465 960);
FORCEPROP 0 LASTPIN (-475 2650) $PN 154
J 0
(-465 2660);
DISPLAY 0.680851 (-465 2660);
PAINT MONO (-465 2660);
FORCEPROP 0 LASTPIN (-475 1000) $PN 247
J 0
(-465 1010);
DISPLAY 0.680851 (-465 1010);
PAINT MONO (-465 1010);
FORCEPROP 0 LASTPIN (-475 2700) $PN 14
J 0
(-465 2710);
DISPLAY 0.680851 (-465 2710);
PAINT MONO (-465 2710);
FORCEPROP 0 LASTPIN (-475 1050) $PN 107
J 0
(-465 1060);
DISPLAY 0.680851 (-465 1060);
PAINT MONO (-465 1060);
FORCEPROP 0 LASTPIN (-475 2750) $PN 16
J 0
(-465 2760);
DISPLAY 0.680851 (-465 2760);
PAINT MONO (-465 2760);
FORCEPROP 0 LASTPIN (-475 1100) $PN 109
J 0
(-465 1110);
DISPLAY 0.680851 (-465 1110);
PAINT MONO (-465 1110);
FORCEPROP 0 LASTPIN (-475 2800) $PN 159
J 0
(-465 2810);
DISPLAY 0.680851 (-465 2810);
PAINT MONO (-465 2810);
FORCEPROP 0 LASTPIN (-475 1150) $PN 252
J 0
(-465 1160);
DISPLAY 0.680851 (-465 1160);
PAINT MONO (-465 1160);
FORCEPROP 0 LASTPIN (-475 2850) $PN 161
J 0
(-465 2860);
DISPLAY 0.680851 (-465 2860);
PAINT MONO (-465 2860);
FORCEPROP 0 LASTPIN (-475 1200) $PN 254
J 0
(-465 1210);
DISPLAY 0.680851 (-465 1210);
PAINT MONO (-465 1210);
FORCEPROP 0 LASTPIN (-475 2900) $PN 18
J 0
(-465 2910);
DISPLAY 0.680851 (-465 2910);
PAINT MONO (-465 2910);
FORCEPROP 0 LASTPIN (-475 1250) $PN 111
J 0
(-465 1260);
DISPLAY 0.680851 (-465 1260);
PAINT MONO (-465 1260);
FORCEPROP 0 LASTPIN (-475 2950) $PN 20
J 0
(-465 2960);
DISPLAY 0.680851 (-465 2960);
PAINT MONO (-465 2960);
FORCEPROP 0 LASTPIN (-475 1300) $PN 113
J 0
(-465 1310);
DISPLAY 0.680851 (-465 1310);
PAINT MONO (-465 1310);
FORCEPROP 0 LASTPIN (-475 3000) $PN 163
J 0
(-465 3010);
DISPLAY 0.680851 (-465 3010);
PAINT MONO (-465 3010);
FORCEPROP 0 LASTPIN (-475 1350) $PN 256
J 0
(-465 1360);
DISPLAY 0.680851 (-465 1360);
PAINT MONO (-465 1360);
FORCEPROP 0 LASTPIN (-475 3050) $PN 165
J 0
(-465 3060);
DISPLAY 0.680851 (-465 3060);
PAINT MONO (-465 3060);
FORCEPROP 0 LASTPIN (-475 1400) $PN 258
J 0
(-465 1410);
DISPLAY 0.680851 (-465 1410);
PAINT MONO (-465 1410);
FORCEPROP 0 LASTPIN (-475 3100) $PN 25
J 0
(-465 3110);
DISPLAY 0.680851 (-465 3110);
PAINT MONO (-465 3110);
FORCEPROP 0 LASTPIN (-475 1450) $PN 118
J 0
(-465 1460);
DISPLAY 0.680851 (-465 1460);
PAINT MONO (-465 1460);
FORCEPROP 0 LASTPIN (-475 3150) $PN 27
J 0
(-465 3160);
DISPLAY 0.680851 (-465 3160);
PAINT MONO (-465 3160);
FORCEPROP 0 LASTPIN (-475 1500) $PN 120
J 0
(-465 1510);
DISPLAY 0.680851 (-465 1510);
PAINT MONO (-465 1510);
FORCEPROP 0 LASTPIN (-475 3200) $PN 170
J 0
(-465 3210);
DISPLAY 0.680851 (-465 3210);
PAINT MONO (-465 3210);
FORCEPROP 0 LASTPIN (-475 1550) $PN 263
J 0
(-465 1560);
DISPLAY 0.680851 (-465 1560);
PAINT MONO (-465 1560);
FORCEPROP 0 LASTPIN (-475 3250) $PN 172
J 0
(-465 3260);
DISPLAY 0.680851 (-465 3260);
PAINT MONO (-465 3260);
FORCEPROP 0 LASTPIN (-475 1600) $PN 265
J 0
(-465 1610);
DISPLAY 0.680851 (-465 1610);
PAINT MONO (-465 1610);
FORCEPROP 0 LASTPIN (-475 3300) $PN 29
J 0
(-465 3310);
DISPLAY 0.680851 (-465 3310);
PAINT MONO (-465 3310);
FORCEPROP 0 LASTPIN (-475 1650) $PN 122
J 0
(-465 1660);
DISPLAY 0.680851 (-465 1660);
PAINT MONO (-465 1660);
FORCEPROP 0 LASTPIN (-475 3350) $PN 31
J 0
(-465 3360);
DISPLAY 0.680851 (-465 3360);
PAINT MONO (-465 3360);
FORCEPROP 0 LASTPIN (-475 1700) $PN 124
J 0
(-465 1710);
DISPLAY 0.680851 (-465 1710);
PAINT MONO (-465 1710);
FORCEPROP 0 LASTPIN (-475 3400) $PN 174
J 0
(-465 3410);
DISPLAY 0.680851 (-465 3410);
PAINT MONO (-465 3410);
FORCEPROP 0 LASTPIN (-475 1750) $PN 267
J 0
(-465 1760);
DISPLAY 0.680851 (-465 1760);
PAINT MONO (-465 1760);
FORCEPROP 0 LASTPIN (-475 3450) $PN 176
J 0
(-465 3460);
DISPLAY 0.680851 (-465 3460);
PAINT MONO (-465 3460);
FORCEPROP 0 LASTPIN (-475 1800) $PN 269
J 0
(-465 1810);
DISPLAY 0.680851 (-465 1810);
PAINT MONO (-465 1810);
FORCEPROP 0 LASTPIN (-475 3500) $PN 36
J 0
(-465 3510);
DISPLAY 0.680851 (-465 3510);
PAINT MONO (-465 3510);
FORCEPROP 0 LASTPIN (-475 1850) $PN 129
J 0
(-465 1860);
DISPLAY 0.680851 (-465 1860);
PAINT MONO (-465 1860);
FORCEPROP 0 LASTPIN (-475 3550) $PN 38
J 0
(-465 3560);
DISPLAY 0.680851 (-465 3560);
PAINT MONO (-465 3560);
FORCEPROP 0 LASTPIN (-475 1900) $PN 131
J 0
(-465 1910);
DISPLAY 0.680851 (-465 1910);
PAINT MONO (-465 1910);
FORCEPROP 0 LASTPIN (-475 3600) $PN 181
J 0
(-465 3610);
DISPLAY 0.680851 (-465 3610);
PAINT MONO (-465 3610);
FORCEPROP 0 LASTPIN (-475 1950) $PN 274
J 0
(-465 1960);
DISPLAY 0.680851 (-465 1960);
PAINT MONO (-465 1960);
FORCEPROP 0 LASTPIN (-475 3650) $PN 183
J 0
(-465 3660);
DISPLAY 0.680851 (-465 3660);
PAINT MONO (-465 3660);
FORCEPROP 0 LASTPIN (-475 2000) $PN 276
J 0
(-465 2010);
DISPLAY 0.680851 (-465 2010);
PAINT MONO (-465 2010);
FORCEPROP 0 LASTPIN (-475 3700) $PN 40
J 0
(-465 3710);
DISPLAY 0.680851 (-465 3710);
PAINT MONO (-465 3710);
FORCEPROP 0 LASTPIN (-475 2050) $PN 133
J 0
(-465 2060);
DISPLAY 0.680851 (-465 2060);
PAINT MONO (-465 2060);
FORCEPROP 0 LASTPIN (-475 3750) $PN 42
J 0
(-465 3760);
DISPLAY 0.680851 (-465 3760);
PAINT MONO (-465 3760);
FORCEPROP 0 LASTPIN (-475 2100) $PN 135
J 0
(-465 2110);
DISPLAY 0.680851 (-465 2110);
PAINT MONO (-465 2110);
FORCEPROP 0 LASTPIN (-475 3800) $PN 185
J 0
(-465 3810);
DISPLAY 0.680851 (-465 3810);
PAINT MONO (-465 3810);
FORCEPROP 0 LASTPIN (-475 2150) $PN 278
J 0
(-465 2160);
DISPLAY 0.680851 (-465 2160);
PAINT MONO (-465 2160);
FORCEPROP 0 LASTPIN (-475 3850) $PN 187
J 0
(-465 3860);
DISPLAY 0.680851 (-465 3860);
PAINT MONO (-465 3860);
FORCEPROP 0 LASTPIN (-475 2200) $PN 280
J 0
(-465 2210);
DISPLAY 0.680851 (-465 2210);
PAINT MONO (-465 2210);
FORCEPROP 0 LASTPIN (-475 3900) $PN 47
J 0
(-465 3910);
DISPLAY 0.680851 (-465 3910);
PAINT MONO (-465 3910);
FORCEPROP 0 LASTPIN (-475 2250) $PN 140
J 0
(-465 2260);
DISPLAY 0.680851 (-465 2260);
PAINT MONO (-465 2260);
FORCEPROP 0 LASTPIN (-475 3950) $PN 49
J 0
(-465 3960);
DISPLAY 0.680851 (-465 3960);
PAINT MONO (-465 3960);
FORCEPROP 0 LASTPIN (-475 2300) $PN 142
J 0
(-465 2310);
DISPLAY 0.680851 (-465 2310);
PAINT MONO (-465 2310);
FORCEPROP 0 LASTPIN (-475 4000) $PN 192
J 0
(-465 4010);
DISPLAY 0.680851 (-465 4010);
PAINT MONO (-465 4010);
FORCEPROP 0 LASTPIN (-475 2350) $PN 285
J 0
(-465 2360);
DISPLAY 0.680851 (-465 2360);
PAINT MONO (-465 2360);
FORCEPROP 0 LASTPIN (-475 4050) $PN 194
J 0
(-465 4060);
DISPLAY 0.680851 (-465 4060);
PAINT MONO (-465 4060);
FORCEPROP 0 LASTPIN (-475 2400) $PN 287
J 0
(-465 2410);
DISPLAY 0.680851 (-465 2410);
PAINT MONO (-465 2410);
FORCEPROP 0 LASTPIN (-1675 1550) $PN 148
J 2
(-1685 1560);
DISPLAY 0.680851 (-1685 1560);
PAINT MONO (-1685 1560);
FORCEPROP 0 LASTPIN (-1675 1450) $PN 4
J 2
(-1685 1460);
DISPLAY 0.680851 (-1685 1460);
PAINT MONO (-1685 1460);
FORCEPROP 0 LASTPIN (-1675 1500) $PN 5
J 2
(-1685 1510);
DISPLAY 0.680851 (-1685 1510);
PAINT MONO (-1685 1510);
FORCEPROP 0 LASTPIN (-1675 650) $PN 86
J 2
(-1685 660);
DISPLAY 0.680851 (-1685 660);
PAINT MONO (-1685 660);
FORCEPROP 0 LASTPIN (-1675 600) $PN 87
J 2
(-1685 610);
DISPLAY 0.680851 (-1685 610);
PAINT MONO (-1685 610);
FORCEPROP 0 LASTPIN (-1675 3250) $PN 74
J 2
(-1685 3260);
DISPLAY 0.680851 (-1685 3260);
PAINT MONO (-1685 3260);
FORCEPROP 0 LASTPIN (-1675 3200) $PN 227
J 2
(-1685 3210);
DISPLAY 0.680851 (-1685 3210);
PAINT MONO (-1685 3210);
FORCEPROP 0 LASTPIN (-1675 1200) $PN 147
J 2
(-1685 1210);
DISPLAY 0.680851 (-1685 1210);
PAINT MONO (-1685 1210);
FORCEPROP 0 LASTPIN (-1675 1750) $PN 207
J 2
(-1685 1760);
DISPLAY 0.680851 (-1685 1760);
PAINT MONO (-1685 1760);
FORCEPROP 0 LASTPIN (-1675 800) $PN 2
J 2
(-1685 810);
DISPLAY 0.680851 (-1685 810);
PAINT MONO (-1685 810);
FORCEPROP 0 LASTPIN (-1675 850) $PN 144
J 2
(-1685 860);
DISPLAY 0.680851 (-1685 860);
PAINT MONO (-1685 860);
FORCEPROP 0 LASTPIN (-1675 900) $PN 149
J 2
(-1685 910);
DISPLAY 0.680851 (-1685 910);
PAINT MONO (-1685 910);
FORCEPROP 0 LASTPIN (-1675 950) $PN 150
J 2
(-1685 960);
DISPLAY 0.680851 (-1685 960);
PAINT MONO (-1685 960);
FORCEPROP 0 LASTPIN (-1675 1000) $PN 220
J 2
(-1685 1010);
DISPLAY 0.680851 (-1685 1010);
PAINT MONO (-1685 1010);
FORCEPROP 0 LASTPIN (-1675 1050) $PN 231
J 2
(-1685 1060);
DISPLAY 0.680851 (-1685 1060);
PAINT MONO (-1685 1060);
FORCEPROP 0 LASTPIN (-1675 1100) $PN 232
J 2
(-1685 1110);
DISPLAY 0.680851 (-1685 1110);
PAINT MONO (-1685 1110);
FORCEPROP 0 LASTPIN (-1675 1600) $PN 3
J 2
(-1685 1610);
DISPLAY 0.680851 (-1685 1610);
PAINT MONO (-1685 1610);
FORCEPROP 2 LAST CDS_LIB pure_quanta
J 0
(-1075 2325);
DISPLAY INVISIBLE (-1075 2325);
FORCEPROP 1 LAST CDS_LMAN_SYM_OUTLINE -450,1875,450,-1875
J 0
(-1075 2325);
DISPLAY 0.468085 (-1075 2325);
PAINT GREEN (-1075 2325);
DISPLAY INVISIBLE (-1075 2325);
FORCEPROP 1 LAST NEEDS_NO_SIZE TRUE
J 0
(-1075 2325);
DISPLAY 0.723404 (-1075 2325);
PAINT GREEN (-1075 2325);
DISPLAY INVISIBLE (-1075 2325);
FORCEPROP 2 LAST CDS_LOCATION J7
J 0
(-1525 4550);
DISPLAY 1.021277 (-1525 4550);
DISPLAY INVISIBLE (-1525 4550);
FORCEPROP 0 LAST $SEC 1
J 0
(-1525 4575);
DISPLAY 0.680851 (-1525 4575);
PAINT MONO (-1525 4575);
DISPLAY INVISIBLE (-1525 4575);
FORCEPROP 2 LAST CDS_SEC 1
J 0
(-1525 4550);
DISPLAY 1.021277 (-1525 4550);
DISPLAY INVISIBLE (-1525 4550);
FORCEPROP 1 LAST PATH I12
J 0
(-1075 2325);
DISPLAY 0.723404 (-1075 2325);
PAINT GREEN (-1075 2325);
DISPLAY INVISIBLE (-1075 2325);
FORCEADD OFFPAGE..3
(575 4075);
FORCEPROP 2 LAST $XR1 89 
J 0
(879 4075);
DISPLAY 0.638298 (879 4075);
PAINT MONO (879 4075);
FORCEPROP 2 LAST $XR0 23 
J 0
(789 4075);
DISPLAY 0.638298 (789 4075);
PAINT MONO (789 4075);
FORCEPROP 2 LAST CDS_LIB standard
J 2
(575 4075);
DISPLAY INVISIBLE (575 4075);
FORCEPROP 1 LAST OFFPAGE TRUE
J 0
(900 3950);
DISPLAY 0.872340 (900 3950);
DISPLAY INVISIBLE (900 3950);
FORCEPROP 1 LAST COMMENT_BODY TRUE
J 0
(525 3975);
DISPLAY 0.872340 (525 3975);
PAINT GREEN (525 3975);
DISPLAY INVISIBLE (525 3975);
FORCEPROP 2 LAST PATH I120
J 0
(775 4150);
DISPLAY 1.021277 (775 4150);
DISPLAY INVISIBLE (775 4150);
FORCEADD UNIVERSAL_GND..1
(1475 -200);
FORCEPROP 3 LASTPIN (1475 -150) SIG_NAME GND\g
J 0
(1485 -140);
DISPLAY 0.659574 (1485 -140);
PAINT MONO (1485 -140);
DISPLAY INVISIBLE (1485 -140);
FORCEPROP 2 LAST CDS_LIB logical_power
J 0
(1475 -200);
PAINT MONO (1475 -200);
DISPLAY INVISIBLE (1475 -200);
FORCEPROP 1 LAST HDL_POWER GND
J 1
(1500 -275);
DISPLAY 0.872340 (1500 -275);
PAINT GREEN (1500 -275);
DISPLAY INVISIBLE (1500 -275);
FORCEPROP 1 LAST PATH I121
J 0
(1550 -200);
DISPLAY 0.872340 (1550 -200);
PAINT AQUA (1550 -200);
DISPLAY INVISIBLE (1550 -200);
FORCEADD UNIVERSAL_GND..1
(3100 -200);
FORCEPROP 3 LASTPIN (3100 -150) SIG_NAME GND\g
J 0
(3110 -140);
DISPLAY 0.659574 (3110 -140);
PAINT MONO (3110 -140);
DISPLAY INVISIBLE (3110 -140);
FORCEPROP 2 LAST CDS_LIB logical_power
J 0
(3100 -200);
PAINT MONO (3100 -200);
DISPLAY INVISIBLE (3100 -200);
FORCEPROP 1 LAST HDL_POWER GND
J 1
(3125 -275);
DISPLAY 0.872340 (3125 -275);
PAINT GREEN (3125 -275);
DISPLAY INVISIBLE (3125 -275);
FORCEPROP 1 LAST PATH I122
J 0
(3175 -200);
DISPLAY 0.872340 (3175 -200);
PAINT AQUA (3175 -200);
DISPLAY INVISIBLE (3175 -200);
FORCEADD Q_CAP..1
(1475 175);
FORCEPROP 1 LAST PART_NUMBER CH5221MEB00
J 0
(1525 25);
DISPLAY 0.978723 (1525 25);
DISPLAY INVISIBLE (1525 25);
FORCEPROP 1 LAST VOLTAGE 6.3V
J 0
(1525 175);
DISPLAY 0.978723 (1525 175);
FORCEPROP 1 LAST MATERIAL X6S
J 0
(1525 75);
DISPLAY 0.978723 (1525 75);
FORCEPROP 1 LAST VALUE 2.2UF
J 0
(1525 225);
DISPLAY 0.978723 (1525 225);
FORCEPROP 1 LAST TOLERANCE 20%
J 0
(1525 125);
DISPLAY 0.978723 (1525 125);
FORCEPROP 1 LAST PACK_TYPE C0402
J 0
(1525 -25);
DISPLAY 0.978723 (1525 -25);
FORCEPROP 1 LAST $LOCATION C20
J 0
(1525 275);
DISPLAY 0.978723 (1525 275);
FORCEPROP 1 LASTPIN (1475 275) $PN 1
J 0
(1485 255);
DISPLAY 0.787234 (1485 255);
FORCEPROP 1 LASTPIN (1475 75) $PN 2
J 0
(1485 55);
DISPLAY 0.787234 (1485 55);
FORCEPROP 2 LAST CDS_LIB pure_quanta
J 0
(1475 175);
PAINT MONO (1475 175);
DISPLAY INVISIBLE (1475 175);
FORCEPROP 2 LAST CDS_LOCATION C20
J 0
(1525 375);
DISPLAY 1.021277 (1525 375);
DISPLAY INVISIBLE (1525 375);
FORCEPROP 2 LAST $SEC 1
J 0
(1525 375);
DISPLAY 0.680851 (1525 375);
PAINT MONO (1525 375);
DISPLAY INVISIBLE (1525 375);
FORCEPROP 2 LAST CDS_SEC 1
J 0
(1525 375);
DISPLAY 1.021277 (1525 375);
DISPLAY INVISIBLE (1525 375);
FORCEPROP 1 LAST PATH I123
J 0
(1525 325);
DISPLAY 0.978723 (1525 325);
PAINT WHITE (1525 325);
DISPLAY INVISIBLE (1525 325);
FORCEADD VCC_CORE..1
(1475 500);
FORCEPROP 3 LASTPIN (1475 450) SIG_NAME P3V3_AUX\g
J 0
(1485 460);
DISPLAY 0.659574 (1485 460);
PAINT MONO (1485 460);
DISPLAY INVISIBLE (1485 460);
FORCEPROP 1 LAST HDL_POWER P3V3_AUX
J 1
(1475 550);
DISPLAY 1.148936 (1475 550);
PAINT GREEN (1475 550);
FORCEPROP 2 LAST CDS_LIB logical_power
J 0
(1475 500);
PAINT MONO (1475 500);
DISPLAY INVISIBLE (1475 500);
FORCEPROP 1 LAST PATH I124
J 0
(1525 525);
DISPLAY 0.872340 (1525 525);
PAINT AQUA (1525 525);
DISPLAY INVISIBLE (1525 525);
FORCEADD Q_CAP..1
(2475 175);
FORCEPROP 1 LAST PART_NUMBER CH6103KEA00
J 0
(2525 25);
DISPLAY 0.978723 (2525 25);
DISPLAY INVISIBLE (2525 25);
FORCEPROP 1 LAST MATERIAL X6S
J 0
(2525 75);
DISPLAY 0.978723 (2525 75);
FORCEPROP 1 LAST PACK_TYPE C0805
J 0
(2525 -25);
DISPLAY 0.978723 (2525 -25);
FORCEPROP 1 LAST TOLERANCE 10%
J 0
(2525 125);
DISPLAY 0.978723 (2525 125);
FORCEPROP 1 LAST VALUE 10UF
J 0
(2525 225);
DISPLAY 0.978723 (2525 225);
FORCEPROP 1 LAST VOLTAGE 16V
J 0
(2525 175);
DISPLAY 0.978723 (2525 175);
FORCEPROP 1 LAST $LOCATION C21
J 0
(2525 275);
DISPLAY 0.978723 (2525 275);
FORCEPROP 1 LASTPIN (2475 275) $PN 1
J 0
(2485 255);
DISPLAY 0.787234 (2485 255);
FORCEPROP 1 LASTPIN (2475 75) $PN 2
J 0
(2485 55);
DISPLAY 0.787234 (2485 55);
FORCEPROP 2 LAST CDS_LIB pure_quanta
J 0
(2475 175);
PAINT MONO (2475 175);
DISPLAY INVISIBLE (2475 175);
FORCEPROP 2 LAST CDS_LOCATION C21
J 0
(2525 375);
DISPLAY 1.021277 (2525 375);
DISPLAY INVISIBLE (2525 375);
FORCEPROP 2 LAST $SEC 1
J 0
(2525 375);
DISPLAY 0.680851 (2525 375);
PAINT MONO (2525 375);
DISPLAY INVISIBLE (2525 375);
FORCEPROP 2 LAST CDS_SEC 1
J 0
(2525 375);
DISPLAY 1.021277 (2525 375);
DISPLAY INVISIBLE (2525 375);
FORCEPROP 1 LAST PATH I126
J 0
(2525 325);
DISPLAY 0.978723 (2525 325);
PAINT WHITE (2525 325);
DISPLAY INVISIBLE (2525 325);
FORCEADD VCC_CORE..1
(2475 500);
FORCEPROP 3 LASTPIN (2475 450) SIG_NAME P12V_S3_AUX_CPU0_NVDIMM\g
J 0
(2485 460);
DISPLAY 0.659574 (2485 460);
PAINT MONO (2485 460);
DISPLAY INVISIBLE (2485 460);
FORCEPROP 1 LAST HDL_POWER P12V_S3_AUX_CPU0_NVDIMM
J 1
(2475 550);
DISPLAY 1.148936 (2475 550);
PAINT GREEN (2475 550);
FORCEPROP 2 LAST CDS_LIB logical_power
J 0
(2475 500);
PAINT MONO (2475 500);
DISPLAY INVISIBLE (2475 500);
FORCEPROP 1 LAST PATH I127
J 0
(2525 525);
DISPLAY 0.872340 (2525 525);
PAINT AQUA (2525 525);
DISPLAY INVISIBLE (2525 525);
FORCEADD TAP..1
(2500 2200);
FORCEPROP 3 LASTPIN (2450 2200) SIG_NAME M_D_CPU0_SB_DQS_DP<1>
J 0
(2460 2210);
DISPLAY 0.659574 (2460 2210);
PAINT MONO (2460 2210);
DISPLAY INVISIBLE (2460 2210);
FORCEPROP 1 LASTPIN (2450 2200) BN 1
J 0
(2438 2208);
DISPLAY 0.680851 (2438 2208);
PAINT GREEN (2438 2208);
FORCEPROP 2 LAST CDS_LIB standard
J 0
(2500 2200);
DISPLAY INVISIBLE (2500 2200);
FORCEPROP 1 LAST BODY_TYPE PLUMBING
J 0
(2500 2250);
DISPLAY 0.872340 (2500 2250);
PAINT GREEN (2500 2250);
DISPLAY INVISIBLE (2500 2250);
FORCEPROP 1 LAST HDL_TAP TRUE
J 0
(2825 2075);
DISPLAY 0.872340 (2825 2075);
DISPLAY INVISIBLE (2825 2075);
FORCEPROP 1 LAST PATH I128
J 0
(2498 2200);
DISPLAY 0.872340 (2498 2200);
PAINT GREEN (2498 2200);
DISPLAY INVISIBLE (2498 2200);
FORCEADD TAP..1
(2500 2100);
FORCEPROP 3 LASTPIN (2450 2100) SIG_NAME M_D_CPU0_SB_DQS_DP<0>
J 0
(2460 2110);
DISPLAY 0.659574 (2460 2110);
PAINT MONO (2460 2110);
DISPLAY INVISIBLE (2460 2110);
FORCEPROP 1 LASTPIN (2450 2100) BN 0
J 0
(2438 2108);
DISPLAY 0.680851 (2438 2108);
PAINT GREEN (2438 2108);
FORCEPROP 2 LAST CDS_LIB standard
J 0
(2500 2100);
PAINT MONO (2500 2100);
DISPLAY INVISIBLE (2500 2100);
FORCEPROP 1 LAST BODY_TYPE PLUMBING
J 0
(2500 2150);
DISPLAY 0.872340 (2500 2150);
PAINT GREEN (2500 2150);
DISPLAY INVISIBLE (2500 2150);
FORCEPROP 1 LAST HDL_TAP TRUE
J 0
(2825 1975);
DISPLAY 0.872340 (2825 1975);
DISPLAY INVISIBLE (2825 1975);
FORCEPROP 1 LAST PATH I129
J 0
(2498 2100);
DISPLAY 0.872340 (2498 2100);
PAINT GREEN (2498 2100);
DISPLAY INVISIBLE (2498 2100);
FORCEADD TAP..1
R 2
(-1900 1850);
FORCEPROP 3 LASTPIN (-1850 1850) SIG_NAME M_D_CPU0_SB_CB<0>
J 0
(-1840 1860);
DISPLAY 0.659574 (-1840 1860);
PAINT MONO (-1840 1860);
DISPLAY INVISIBLE (-1840 1860);
FORCEPROP 1 LASTPIN (-1850 1850) BN 0
J 2
(-1838 1858);
DISPLAY 0.680851 (-1838 1858);
PAINT GREEN (-1838 1858);
FORCEPROP 2 LAST CDS_LIB standard
J 0
(-1900 1850);
PAINT MONO (-1900 1850);
DISPLAY INVISIBLE (-1900 1850);
FORCEPROP 1 LAST BODY_TYPE PLUMBING
J 2
(-1900 1900);
DISPLAY 0.872340 (-1900 1900);
PAINT GREEN (-1900 1900);
DISPLAY INVISIBLE (-1900 1900);
FORCEPROP 1 LAST HDL_TAP TRUE
J 2
(-2225 1725);
DISPLAY 0.872340 (-2225 1725);
DISPLAY INVISIBLE (-2225 1725);
FORCEPROP 1 LAST PATH I13
J 2
(-1898 1850);
DISPLAY 0.872340 (-1898 1850);
PAINT GREEN (-1898 1850);
DISPLAY INVISIBLE (-1898 1850);
FORCEADD TAP..1
(2500 2300);
FORCEPROP 3 LASTPIN (2450 2300) SIG_NAME M_D_CPU0_SB_DQS_DP<2>
J 0
(2460 2310);
DISPLAY 0.659574 (2460 2310);
PAINT MONO (2460 2310);
DISPLAY INVISIBLE (2460 2310);
FORCEPROP 1 LASTPIN (2450 2300) BN 2
J 0
(2438 2308);
DISPLAY 0.680851 (2438 2308);
PAINT GREEN (2438 2308);
FORCEPROP 2 LAST CDS_LIB standard
J 0
(2500 2300);
DISPLAY INVISIBLE (2500 2300);
FORCEPROP 1 LAST BODY_TYPE PLUMBING
J 0
(2500 2350);
DISPLAY 0.872340 (2500 2350);
PAINT GREEN (2500 2350);
DISPLAY INVISIBLE (2500 2350);
FORCEPROP 1 LAST HDL_TAP TRUE
J 0
(2825 2175);
DISPLAY 0.872340 (2825 2175);
DISPLAY INVISIBLE (2825 2175);
FORCEPROP 1 LAST PATH I130
J 0
(2498 2300);
DISPLAY 0.872340 (2498 2300);
PAINT GREEN (2498 2300);
DISPLAY INVISIBLE (2498 2300);
FORCEADD TAP..1
(2500 2400);
FORCEPROP 3 LASTPIN (2450 2400) SIG_NAME M_D_CPU0_SB_DQS_DP<3>
J 0
(2460 2410);
DISPLAY 0.659574 (2460 2410);
PAINT MONO (2460 2410);
DISPLAY INVISIBLE (2460 2410);
FORCEPROP 1 LASTPIN (2450 2400) BN 3
J 0
(2438 2408);
DISPLAY 0.680851 (2438 2408);
PAINT GREEN (2438 2408);
FORCEPROP 2 LAST CDS_LIB standard
J 0
(2500 2400);
PAINT MONO (2500 2400);
DISPLAY INVISIBLE (2500 2400);
FORCEPROP 1 LAST BODY_TYPE PLUMBING
J 0
(2500 2450);
DISPLAY 0.872340 (2500 2450);
PAINT GREEN (2500 2450);
DISPLAY INVISIBLE (2500 2450);
FORCEPROP 1 LAST HDL_TAP TRUE
J 0
(2825 2275);
DISPLAY 0.872340 (2825 2275);
DISPLAY INVISIBLE (2825 2275);
FORCEPROP 1 LAST PATH I131
J 0
(2498 2400);
DISPLAY 0.872340 (2498 2400);
PAINT GREEN (2498 2400);
DISPLAY INVISIBLE (2498 2400);
FORCEADD TAP..1
(2500 2500);
FORCEPROP 3 LASTPIN (2450 2500) SIG_NAME M_D_CPU0_SB_DQS_DP<4>
J 0
(2460 2510);
DISPLAY 0.659574 (2460 2510);
PAINT MONO (2460 2510);
DISPLAY INVISIBLE (2460 2510);
FORCEPROP 1 LASTPIN (2450 2500) BN 4
J 0
(2438 2508);
DISPLAY 0.680851 (2438 2508);
PAINT GREEN (2438 2508);
FORCEPROP 2 LAST CDS_LIB standard
J 0
(2500 2500);
PAINT MONO (2500 2500);
DISPLAY INVISIBLE (2500 2500);
FORCEPROP 1 LAST BODY_TYPE PLUMBING
J 0
(2500 2550);
DISPLAY 0.872340 (2500 2550);
PAINT GREEN (2500 2550);
DISPLAY INVISIBLE (2500 2550);
FORCEPROP 1 LAST HDL_TAP TRUE
J 0
(2825 2375);
DISPLAY 0.872340 (2825 2375);
DISPLAY INVISIBLE (2825 2375);
FORCEPROP 1 LAST PATH I132
J 0
(2498 2500);
DISPLAY 0.872340 (2498 2500);
PAINT GREEN (2498 2500);
DISPLAY INVISIBLE (2498 2500);
FORCEADD TAP..1
(2500 2700);
FORCEPROP 3 LASTPIN (2450 2700) SIG_NAME M_D_CPU0_SB_DQS_DP<6>
J 0
(2460 2710);
DISPLAY 0.659574 (2460 2710);
PAINT MONO (2460 2710);
DISPLAY INVISIBLE (2460 2710);
FORCEPROP 1 LASTPIN (2450 2700) BN 6
J 0
(2438 2708);
DISPLAY 0.680851 (2438 2708);
PAINT GREEN (2438 2708);
FORCEPROP 2 LAST CDS_LIB standard
J 0
(2500 2700);
DISPLAY INVISIBLE (2500 2700);
FORCEPROP 1 LAST BODY_TYPE PLUMBING
J 0
(2500 2750);
DISPLAY 0.872340 (2500 2750);
PAINT GREEN (2500 2750);
DISPLAY INVISIBLE (2500 2750);
FORCEPROP 1 LAST HDL_TAP TRUE
J 0
(2825 2575);
DISPLAY 0.872340 (2825 2575);
DISPLAY INVISIBLE (2825 2575);
FORCEPROP 1 LAST PATH I133
J 0
(2498 2700);
DISPLAY 0.872340 (2498 2700);
PAINT GREEN (2498 2700);
DISPLAY INVISIBLE (2498 2700);
FORCEADD TAP..1
(2500 2600);
FORCEPROP 3 LASTPIN (2450 2600) SIG_NAME M_D_CPU0_SB_DQS_DP<5>
J 0
(2460 2610);
DISPLAY 0.659574 (2460 2610);
PAINT MONO (2460 2610);
DISPLAY INVISIBLE (2460 2610);
FORCEPROP 1 LASTPIN (2450 2600) BN 5
J 0
(2438 2608);
DISPLAY 0.680851 (2438 2608);
PAINT GREEN (2438 2608);
FORCEPROP 2 LAST CDS_LIB standard
J 0
(2500 2600);
DISPLAY INVISIBLE (2500 2600);
FORCEPROP 1 LAST BODY_TYPE PLUMBING
J 0
(2500 2650);
DISPLAY 0.872340 (2500 2650);
PAINT GREEN (2500 2650);
DISPLAY INVISIBLE (2500 2650);
FORCEPROP 1 LAST HDL_TAP TRUE
J 0
(2825 2475);
DISPLAY 0.872340 (2825 2475);
DISPLAY INVISIBLE (2825 2475);
FORCEPROP 1 LAST PATH I134
J 0
(2498 2600);
DISPLAY 0.872340 (2498 2600);
PAINT GREEN (2498 2600);
DISPLAY INVISIBLE (2498 2600);
FORCEADD TAP..1
(2500 2800);
FORCEPROP 3 LASTPIN (2450 2800) SIG_NAME M_D_CPU0_SB_DQS_DP<7>
J 0
(2460 2810);
DISPLAY 0.659574 (2460 2810);
PAINT MONO (2460 2810);
DISPLAY INVISIBLE (2460 2810);
FORCEPROP 1 LASTPIN (2450 2800) BN 7
J 0
(2438 2808);
DISPLAY 0.680851 (2438 2808);
PAINT GREEN (2438 2808);
FORCEPROP 2 LAST CDS_LIB standard
J 0
(2500 2800);
DISPLAY INVISIBLE (2500 2800);
FORCEPROP 1 LAST BODY_TYPE PLUMBING
J 0
(2500 2850);
DISPLAY 0.872340 (2500 2850);
PAINT GREEN (2500 2850);
DISPLAY INVISIBLE (2500 2850);
FORCEPROP 1 LAST HDL_TAP TRUE
J 0
(2825 2675);
DISPLAY 0.872340 (2825 2675);
DISPLAY INVISIBLE (2825 2675);
FORCEPROP 1 LAST PATH I135
J 0
(2498 2800);
DISPLAY 0.872340 (2498 2800);
PAINT GREEN (2498 2800);
DISPLAY INVISIBLE (2498 2800);
FORCEADD TAP..1
(2500 2900);
FORCEPROP 3 LASTPIN (2450 2900) SIG_NAME M_D_CPU0_SB_DQS_DP<8>
J 0
(2460 2910);
DISPLAY 0.659574 (2460 2910);
PAINT MONO (2460 2910);
DISPLAY INVISIBLE (2460 2910);
FORCEPROP 1 LASTPIN (2450 2900) BN 8
J 0
(2438 2908);
DISPLAY 0.680851 (2438 2908);
PAINT GREEN (2438 2908);
FORCEPROP 2 LAST CDS_LIB standard
J 0
(2500 2900);
DISPLAY INVISIBLE (2500 2900);
FORCEPROP 1 LAST BODY_TYPE PLUMBING
J 0
(2500 2950);
DISPLAY 0.872340 (2500 2950);
PAINT GREEN (2500 2950);
DISPLAY INVISIBLE (2500 2950);
FORCEPROP 1 LAST HDL_TAP TRUE
J 0
(2825 2775);
DISPLAY 0.872340 (2825 2775);
DISPLAY INVISIBLE (2825 2775);
FORCEPROP 1 LAST PATH I136
J 0
(2498 2900);
DISPLAY 0.872340 (2498 2900);
PAINT GREEN (2498 2900);
DISPLAY INVISIBLE (2498 2900);
FORCEADD TAP..1
(2675 2050);
FORCEPROP 3 LASTPIN (2625 2050) SIG_NAME M_D_CPU0_SB_DQS_DN<0>
J 0
(2635 2060);
DISPLAY 0.659574 (2635 2060);
PAINT MONO (2635 2060);
DISPLAY INVISIBLE (2635 2060);
FORCEPROP 1 LASTPIN (2625 2050) BN 0
J 0
(2613 2058);
DISPLAY 0.680851 (2613 2058);
PAINT GREEN (2613 2058);
FORCEPROP 2 LAST CDS_LIB standard
J 0
(2675 2050);
PAINT MONO (2675 2050);
DISPLAY INVISIBLE (2675 2050);
FORCEPROP 1 LAST BODY_TYPE PLUMBING
J 0
(2675 2100);
DISPLAY 0.872340 (2675 2100);
PAINT GREEN (2675 2100);
DISPLAY INVISIBLE (2675 2100);
FORCEPROP 1 LAST HDL_TAP TRUE
J 0
(3000 1925);
DISPLAY 0.872340 (3000 1925);
DISPLAY INVISIBLE (3000 1925);
FORCEPROP 1 LAST PATH I137
J 0
(2673 2050);
DISPLAY 0.872340 (2673 2050);
PAINT GREEN (2673 2050);
DISPLAY INVISIBLE (2673 2050);
FORCEADD TAP..1
(2675 2150);
FORCEPROP 3 LASTPIN (2625 2150) SIG_NAME M_D_CPU0_SB_DQS_DN<1>
J 0
(2635 2160);
DISPLAY 0.659574 (2635 2160);
PAINT MONO (2635 2160);
DISPLAY INVISIBLE (2635 2160);
FORCEPROP 1 LASTPIN (2625 2150) BN 1
J 0
(2613 2158);
DISPLAY 0.680851 (2613 2158);
PAINT GREEN (2613 2158);
FORCEPROP 2 LAST CDS_LIB standard
J 0
(2675 2150);
DISPLAY INVISIBLE (2675 2150);
FORCEPROP 1 LAST BODY_TYPE PLUMBING
J 0
(2675 2200);
DISPLAY 0.872340 (2675 2200);
PAINT GREEN (2675 2200);
DISPLAY INVISIBLE (2675 2200);
FORCEPROP 1 LAST HDL_TAP TRUE
J 0
(3000 2025);
DISPLAY 0.872340 (3000 2025);
DISPLAY INVISIBLE (3000 2025);
FORCEPROP 1 LAST PATH I138
J 0
(2673 2150);
DISPLAY 0.872340 (2673 2150);
PAINT GREEN (2673 2150);
DISPLAY INVISIBLE (2673 2150);
FORCEADD TAP..1
(2675 2250);
FORCEPROP 3 LASTPIN (2625 2250) SIG_NAME M_D_CPU0_SB_DQS_DN<2>
J 0
(2635 2260);
DISPLAY 0.659574 (2635 2260);
PAINT MONO (2635 2260);
DISPLAY INVISIBLE (2635 2260);
FORCEPROP 1 LASTPIN (2625 2250) BN 2
J 0
(2613 2258);
DISPLAY 0.680851 (2613 2258);
PAINT GREEN (2613 2258);
FORCEPROP 2 LAST CDS_LIB standard
J 0
(2675 2250);
DISPLAY INVISIBLE (2675 2250);
FORCEPROP 1 LAST BODY_TYPE PLUMBING
J 0
(2675 2300);
DISPLAY 0.872340 (2675 2300);
PAINT GREEN (2675 2300);
DISPLAY INVISIBLE (2675 2300);
FORCEPROP 1 LAST HDL_TAP TRUE
J 0
(3000 2125);
DISPLAY 0.872340 (3000 2125);
DISPLAY INVISIBLE (3000 2125);
FORCEPROP 1 LAST PATH I139
J 0
(2673 2250);
DISPLAY 0.872340 (2673 2250);
PAINT GREEN (2673 2250);
DISPLAY INVISIBLE (2673 2250);
FORCEADD TAP..1
R 2
(-1900 1900);
FORCEPROP 3 LASTPIN (-1850 1900) SIG_NAME M_D_CPU0_SB_CB<1>
J 0
(-1840 1910);
DISPLAY 0.659574 (-1840 1910);
PAINT MONO (-1840 1910);
DISPLAY INVISIBLE (-1840 1910);
FORCEPROP 1 LASTPIN (-1850 1900) BN 1
J 2
(-1838 1908);
DISPLAY 0.680851 (-1838 1908);
PAINT GREEN (-1838 1908);
FORCEPROP 2 LAST CDS_LIB standard
J 0
(-1900 1900);
DISPLAY INVISIBLE (-1900 1900);
FORCEPROP 1 LAST BODY_TYPE PLUMBING
J 2
(-1900 1950);
DISPLAY 0.872340 (-1900 1950);
PAINT GREEN (-1900 1950);
DISPLAY INVISIBLE (-1900 1950);
FORCEPROP 1 LAST HDL_TAP TRUE
J 2
(-2225 1775);
DISPLAY 0.872340 (-2225 1775);
DISPLAY INVISIBLE (-2225 1775);
FORCEPROP 1 LAST PATH I14
J 2
(-1898 1900);
DISPLAY 0.872340 (-1898 1900);
PAINT GREEN (-1898 1900);
DISPLAY INVISIBLE (-1898 1900);
FORCEADD TAP..1
(2675 2350);
FORCEPROP 3 LASTPIN (2625 2350) SIG_NAME M_D_CPU0_SB_DQS_DN<3>
J 0
(2635 2360);
DISPLAY 0.659574 (2635 2360);
PAINT MONO (2635 2360);
DISPLAY INVISIBLE (2635 2360);
FORCEPROP 1 LASTPIN (2625 2350) BN 3
J 0
(2613 2358);
DISPLAY 0.680851 (2613 2358);
PAINT GREEN (2613 2358);
FORCEPROP 2 LAST CDS_LIB standard
J 0
(2675 2350);
PAINT MONO (2675 2350);
DISPLAY INVISIBLE (2675 2350);
FORCEPROP 1 LAST BODY_TYPE PLUMBING
J 0
(2675 2400);
DISPLAY 0.872340 (2675 2400);
PAINT GREEN (2675 2400);
DISPLAY INVISIBLE (2675 2400);
FORCEPROP 1 LAST HDL_TAP TRUE
J 0
(3000 2225);
DISPLAY 0.872340 (3000 2225);
DISPLAY INVISIBLE (3000 2225);
FORCEPROP 1 LAST PATH I140
J 0
(2673 2350);
DISPLAY 0.872340 (2673 2350);
PAINT GREEN (2673 2350);
DISPLAY INVISIBLE (2673 2350);
FORCEADD TAP..1
(2675 2450);
FORCEPROP 3 LASTPIN (2625 2450) SIG_NAME M_D_CPU0_SB_DQS_DN<4>
J 0
(2635 2460);
DISPLAY 0.659574 (2635 2460);
PAINT MONO (2635 2460);
DISPLAY INVISIBLE (2635 2460);
FORCEPROP 1 LASTPIN (2625 2450) BN 4
J 0
(2613 2458);
DISPLAY 0.680851 (2613 2458);
PAINT GREEN (2613 2458);
FORCEPROP 2 LAST CDS_LIB standard
J 0
(2675 2450);
PAINT MONO (2675 2450);
DISPLAY INVISIBLE (2675 2450);
FORCEPROP 1 LAST BODY_TYPE PLUMBING
J 0
(2675 2500);
DISPLAY 0.872340 (2675 2500);
PAINT GREEN (2675 2500);
DISPLAY INVISIBLE (2675 2500);
FORCEPROP 1 LAST HDL_TAP TRUE
J 0
(3000 2325);
DISPLAY 0.872340 (3000 2325);
DISPLAY INVISIBLE (3000 2325);
FORCEPROP 1 LAST PATH I141
J 0
(2673 2450);
DISPLAY 0.872340 (2673 2450);
PAINT GREEN (2673 2450);
DISPLAY INVISIBLE (2673 2450);
FORCEADD TAP..1
(2675 2550);
FORCEPROP 3 LASTPIN (2625 2550) SIG_NAME M_D_CPU0_SB_DQS_DN<5>
J 0
(2635 2560);
DISPLAY 0.659574 (2635 2560);
PAINT MONO (2635 2560);
DISPLAY INVISIBLE (2635 2560);
FORCEPROP 1 LASTPIN (2625 2550) BN 5
J 0
(2613 2558);
DISPLAY 0.680851 (2613 2558);
PAINT GREEN (2613 2558);
FORCEPROP 2 LAST CDS_LIB standard
J 0
(2675 2550);
DISPLAY INVISIBLE (2675 2550);
FORCEPROP 1 LAST BODY_TYPE PLUMBING
J 0
(2675 2600);
DISPLAY 0.872340 (2675 2600);
PAINT GREEN (2675 2600);
DISPLAY INVISIBLE (2675 2600);
FORCEPROP 1 LAST HDL_TAP TRUE
J 0
(3000 2425);
DISPLAY 0.872340 (3000 2425);
DISPLAY INVISIBLE (3000 2425);
FORCEPROP 1 LAST PATH I142
J 0
(2673 2550);
DISPLAY 0.872340 (2673 2550);
PAINT GREEN (2673 2550);
DISPLAY INVISIBLE (2673 2550);
FORCEADD TAP..1
(2675 2650);
FORCEPROP 3 LASTPIN (2625 2650) SIG_NAME M_D_CPU0_SB_DQS_DN<6>
J 0
(2635 2660);
DISPLAY 0.659574 (2635 2660);
PAINT MONO (2635 2660);
DISPLAY INVISIBLE (2635 2660);
FORCEPROP 1 LASTPIN (2625 2650) BN 6
J 0
(2613 2658);
DISPLAY 0.680851 (2613 2658);
PAINT GREEN (2613 2658);
FORCEPROP 2 LAST CDS_LIB standard
J 0
(2675 2650);
DISPLAY INVISIBLE (2675 2650);
FORCEPROP 1 LAST BODY_TYPE PLUMBING
J 0
(2675 2700);
DISPLAY 0.872340 (2675 2700);
PAINT GREEN (2675 2700);
DISPLAY INVISIBLE (2675 2700);
FORCEPROP 1 LAST HDL_TAP TRUE
J 0
(3000 2525);
DISPLAY 0.872340 (3000 2525);
DISPLAY INVISIBLE (3000 2525);
FORCEPROP 1 LAST PATH I143
J 0
(2673 2650);
DISPLAY 0.872340 (2673 2650);
PAINT GREEN (2673 2650);
DISPLAY INVISIBLE (2673 2650);
FORCEADD TAP..1
(2675 2750);
FORCEPROP 3 LASTPIN (2625 2750) SIG_NAME M_D_CPU0_SB_DQS_DN<7>
J 0
(2635 2760);
DISPLAY 0.659574 (2635 2760);
PAINT MONO (2635 2760);
DISPLAY INVISIBLE (2635 2760);
FORCEPROP 1 LASTPIN (2625 2750) BN 7
J 0
(2613 2758);
DISPLAY 0.680851 (2613 2758);
PAINT GREEN (2613 2758);
FORCEPROP 2 LAST CDS_LIB standard
J 0
(2675 2750);
DISPLAY INVISIBLE (2675 2750);
FORCEPROP 1 LAST BODY_TYPE PLUMBING
J 0
(2675 2800);
DISPLAY 0.872340 (2675 2800);
PAINT GREEN (2675 2800);
DISPLAY INVISIBLE (2675 2800);
FORCEPROP 1 LAST HDL_TAP TRUE
J 0
(3000 2625);
DISPLAY 0.872340 (3000 2625);
DISPLAY INVISIBLE (3000 2625);
FORCEPROP 1 LAST PATH I144
J 0
(2673 2750);
DISPLAY 0.872340 (2673 2750);
PAINT GREEN (2673 2750);
DISPLAY INVISIBLE (2673 2750);
FORCEADD TAP..1
(2675 2950);
FORCEPROP 3 LASTPIN (2625 2950) SIG_NAME M_D_CPU0_SB_DQS_DN<9>
J 0
(2635 2960);
DISPLAY 0.659574 (2635 2960);
PAINT MONO (2635 2960);
DISPLAY INVISIBLE (2635 2960);
FORCEPROP 1 LASTPIN (2625 2950) BN 9
J 0
(2613 2958);
DISPLAY 0.680851 (2613 2958);
PAINT GREEN (2613 2958);
FORCEPROP 2 LAST CDS_LIB standard
J 0
(2675 2950);
DISPLAY INVISIBLE (2675 2950);
FORCEPROP 1 LAST BODY_TYPE PLUMBING
J 0
(2675 3000);
DISPLAY 0.872340 (2675 3000);
PAINT GREEN (2675 3000);
DISPLAY INVISIBLE (2675 3000);
FORCEPROP 1 LAST HDL_TAP TRUE
J 0
(3000 2825);
DISPLAY 0.872340 (3000 2825);
DISPLAY INVISIBLE (3000 2825);
FORCEPROP 1 LAST PATH I145
J 0
(2673 2950);
DISPLAY 0.872340 (2673 2950);
PAINT GREEN (2673 2950);
DISPLAY INVISIBLE (2673 2950);
FORCEADD TAP..1
(2675 2850);
FORCEPROP 3 LASTPIN (2625 2850) SIG_NAME M_D_CPU0_SB_DQS_DN<8>
J 0
(2635 2860);
DISPLAY 0.659574 (2635 2860);
PAINT MONO (2635 2860);
DISPLAY INVISIBLE (2635 2860);
FORCEPROP 1 LASTPIN (2625 2850) BN 8
J 0
(2613 2858);
DISPLAY 0.680851 (2613 2858);
PAINT GREEN (2613 2858);
FORCEPROP 2 LAST CDS_LIB standard
J 0
(2675 2850);
DISPLAY INVISIBLE (2675 2850);
FORCEPROP 1 LAST BODY_TYPE PLUMBING
J 0
(2675 2900);
DISPLAY 0.872340 (2675 2900);
PAINT GREEN (2675 2900);
DISPLAY INVISIBLE (2675 2900);
FORCEPROP 1 LAST HDL_TAP TRUE
J 0
(3000 2725);
DISPLAY 0.872340 (3000 2725);
DISPLAY INVISIBLE (3000 2725);
FORCEPROP 1 LAST PATH I146
J 0
(2673 2850);
DISPLAY 0.872340 (2673 2850);
PAINT GREEN (2673 2850);
DISPLAY INVISIBLE (2673 2850);
FORCEADD TAP..1
(2500 3000);
FORCEPROP 3 LASTPIN (2450 3000) SIG_NAME M_D_CPU0_SB_DQS_DP<9>
J 0
(2460 3010);
DISPLAY 0.659574 (2460 3010);
PAINT MONO (2460 3010);
DISPLAY INVISIBLE (2460 3010);
FORCEPROP 1 LASTPIN (2450 3000) BN 9
J 0
(2438 3008);
DISPLAY 0.680851 (2438 3008);
PAINT GREEN (2438 3008);
FORCEPROP 2 LAST CDS_LIB standard
J 0
(2500 3000);
DISPLAY INVISIBLE (2500 3000);
FORCEPROP 1 LAST BODY_TYPE PLUMBING
J 0
(2500 3050);
DISPLAY 0.872340 (2500 3050);
PAINT GREEN (2500 3050);
DISPLAY INVISIBLE (2500 3050);
FORCEPROP 1 LAST HDL_TAP TRUE
J 0
(2825 2875);
DISPLAY 0.872340 (2825 2875);
DISPLAY INVISIBLE (2825 2875);
FORCEPROP 1 LAST PATH I147
J 0
(2498 3000);
DISPLAY 0.872340 (2498 3000);
PAINT GREEN (2498 3000);
DISPLAY INVISIBLE (2498 3000);
FORCEADD TAP..1
(2500 3150);
FORCEPROP 3 LASTPIN (2450 3150) SIG_NAME M_D_CPU0_SA_DQS_DP<0>
J 0
(2460 3160);
DISPLAY 0.659574 (2460 3160);
PAINT MONO (2460 3160);
DISPLAY INVISIBLE (2460 3160);
FORCEPROP 1 LASTPIN (2450 3150) BN 0
J 0
(2438 3158);
DISPLAY 0.680851 (2438 3158);
PAINT GREEN (2438 3158);
FORCEPROP 2 LAST CDS_LIB standard
J 0
(2500 3150);
PAINT MONO (2500 3150);
DISPLAY INVISIBLE (2500 3150);
FORCEPROP 1 LAST BODY_TYPE PLUMBING
J 0
(2500 3200);
DISPLAY 0.872340 (2500 3200);
PAINT GREEN (2500 3200);
DISPLAY INVISIBLE (2500 3200);
FORCEPROP 1 LAST HDL_TAP TRUE
J 0
(2825 3025);
DISPLAY 0.872340 (2825 3025);
DISPLAY INVISIBLE (2825 3025);
FORCEPROP 1 LAST PATH I148
J 0
(2498 3150);
DISPLAY 0.872340 (2498 3150);
PAINT GREEN (2498 3150);
DISPLAY INVISIBLE (2498 3150);
FORCEADD TAP..1
(2500 3350);
FORCEPROP 3 LASTPIN (2450 3350) SIG_NAME M_D_CPU0_SA_DQS_DP<2>
J 0
(2460 3360);
DISPLAY 0.659574 (2460 3360);
PAINT MONO (2460 3360);
DISPLAY INVISIBLE (2460 3360);
FORCEPROP 1 LASTPIN (2450 3350) BN 2
J 0
(2438 3358);
DISPLAY 0.680851 (2438 3358);
PAINT GREEN (2438 3358);
FORCEPROP 2 LAST CDS_LIB standard
J 0
(2500 3350);
DISPLAY INVISIBLE (2500 3350);
FORCEPROP 1 LAST BODY_TYPE PLUMBING
J 0
(2500 3400);
DISPLAY 0.872340 (2500 3400);
PAINT GREEN (2500 3400);
DISPLAY INVISIBLE (2500 3400);
FORCEPROP 1 LAST HDL_TAP TRUE
J 0
(2825 3225);
DISPLAY 0.872340 (2825 3225);
DISPLAY INVISIBLE (2825 3225);
FORCEPROP 1 LAST PATH I149
J 0
(2498 3350);
DISPLAY 0.872340 (2498 3350);
PAINT GREEN (2498 3350);
DISPLAY INVISIBLE (2498 3350);
FORCEADD OFFPAGE..3
R 2
(-2825 2225);
FORCEPROP 2 LAST $XR1 89 
J 0
(-3164 2225);
DISPLAY 0.638298 (-3164 2225);
PAINT MONO (-3164 2225);
FORCEPROP 2 LAST $XR0 23 
J 0
(-3074 2225);
DISPLAY 0.638298 (-3074 2225);
PAINT MONO (-3074 2225);
FORCEPROP 2 LAST CDS_LIB standard
J 0
(-2825 2225);
PAINT MONO (-2825 2225);
DISPLAY INVISIBLE (-2825 2225);
FORCEPROP 1 LAST OFFPAGE TRUE
J 2
(-3150 2100);
DISPLAY 0.872340 (-3150 2100);
DISPLAY INVISIBLE (-3150 2100);
FORCEPROP 1 LAST COMMENT_BODY TRUE
J 2
(-2775 2125);
DISPLAY 0.872340 (-2775 2125);
PAINT GREEN (-2775 2125);
DISPLAY INVISIBLE (-2775 2125);
FORCEPROP 2 LAST PATH I15
J 0
(-2775 2300);
DISPLAY 1.021277 (-2775 2300);
DISPLAY INVISIBLE (-2775 2300);
FORCEADD TAP..1
(2500 3250);
FORCEPROP 3 LASTPIN (2450 3250) SIG_NAME M_D_CPU0_SA_DQS_DP<1>
J 0
(2460 3260);
DISPLAY 0.659574 (2460 3260);
PAINT MONO (2460 3260);
DISPLAY INVISIBLE (2460 3260);
FORCEPROP 1 LASTPIN (2450 3250) BN 1
J 0
(2438 3258);
DISPLAY 0.680851 (2438 3258);
PAINT GREEN (2438 3258);
FORCEPROP 2 LAST CDS_LIB standard
J 0
(2500 3250);
DISPLAY INVISIBLE (2500 3250);
FORCEPROP 1 LAST BODY_TYPE PLUMBING
J 0
(2500 3300);
DISPLAY 0.872340 (2500 3300);
PAINT GREEN (2500 3300);
DISPLAY INVISIBLE (2500 3300);
FORCEPROP 1 LAST HDL_TAP TRUE
J 0
(2825 3125);
DISPLAY 0.872340 (2825 3125);
DISPLAY INVISIBLE (2825 3125);
FORCEPROP 1 LAST PATH I150
J 0
(2498 3250);
DISPLAY 0.872340 (2498 3250);
PAINT GREEN (2498 3250);
DISPLAY INVISIBLE (2498 3250);
FORCEADD TAP..1
(2500 3450);
FORCEPROP 3 LASTPIN (2450 3450) SIG_NAME M_D_CPU0_SA_DQS_DP<3>
J 0
(2460 3460);
DISPLAY 0.659574 (2460 3460);
PAINT MONO (2460 3460);
DISPLAY INVISIBLE (2460 3460);
FORCEPROP 1 LASTPIN (2450 3450) BN 3
J 0
(2438 3458);
DISPLAY 0.680851 (2438 3458);
PAINT GREEN (2438 3458);
FORCEPROP 2 LAST CDS_LIB standard
J 0
(2500 3450);
PAINT MONO (2500 3450);
DISPLAY INVISIBLE (2500 3450);
FORCEPROP 1 LAST BODY_TYPE PLUMBING
J 0
(2500 3500);
DISPLAY 0.872340 (2500 3500);
PAINT GREEN (2500 3500);
DISPLAY INVISIBLE (2500 3500);
FORCEPROP 1 LAST HDL_TAP TRUE
J 0
(2825 3325);
DISPLAY 0.872340 (2825 3325);
DISPLAY INVISIBLE (2825 3325);
FORCEPROP 1 LAST PATH I151
J 0
(2498 3450);
DISPLAY 0.872340 (2498 3450);
PAINT GREEN (2498 3450);
DISPLAY INVISIBLE (2498 3450);
FORCEADD TAP..1
(2500 3550);
FORCEPROP 3 LASTPIN (2450 3550) SIG_NAME M_D_CPU0_SA_DQS_DP<4>
J 0
(2460 3560);
DISPLAY 0.659574 (2460 3560);
PAINT MONO (2460 3560);
DISPLAY INVISIBLE (2460 3560);
FORCEPROP 1 LASTPIN (2450 3550) BN 4
J 0
(2438 3558);
DISPLAY 0.680851 (2438 3558);
PAINT GREEN (2438 3558);
FORCEPROP 2 LAST CDS_LIB standard
J 0
(2500 3550);
PAINT MONO (2500 3550);
DISPLAY INVISIBLE (2500 3550);
FORCEPROP 1 LAST BODY_TYPE PLUMBING
J 0
(2500 3600);
DISPLAY 0.872340 (2500 3600);
PAINT GREEN (2500 3600);
DISPLAY INVISIBLE (2500 3600);
FORCEPROP 1 LAST HDL_TAP TRUE
J 0
(2825 3425);
DISPLAY 0.872340 (2825 3425);
DISPLAY INVISIBLE (2825 3425);
FORCEPROP 1 LAST PATH I152
J 0
(2498 3550);
DISPLAY 0.872340 (2498 3550);
PAINT GREEN (2498 3550);
DISPLAY INVISIBLE (2498 3550);
FORCEADD TAP..1
(2500 3650);
FORCEPROP 3 LASTPIN (2450 3650) SIG_NAME M_D_CPU0_SA_DQS_DP<5>
J 0
(2460 3660);
DISPLAY 0.659574 (2460 3660);
PAINT MONO (2460 3660);
DISPLAY INVISIBLE (2460 3660);
FORCEPROP 1 LASTPIN (2450 3650) BN 5
J 0
(2438 3658);
DISPLAY 0.680851 (2438 3658);
PAINT GREEN (2438 3658);
FORCEPROP 2 LAST CDS_LIB standard
J 0
(2500 3650);
DISPLAY INVISIBLE (2500 3650);
FORCEPROP 1 LAST BODY_TYPE PLUMBING
J 0
(2500 3700);
DISPLAY 0.872340 (2500 3700);
PAINT GREEN (2500 3700);
DISPLAY INVISIBLE (2500 3700);
FORCEPROP 1 LAST HDL_TAP TRUE
J 0
(2825 3525);
DISPLAY 0.872340 (2825 3525);
DISPLAY INVISIBLE (2825 3525);
FORCEPROP 1 LAST PATH I153
J 0
(2498 3650);
DISPLAY 0.872340 (2498 3650);
PAINT GREEN (2498 3650);
DISPLAY INVISIBLE (2498 3650);
FORCEADD TAP..1
(2500 3750);
FORCEPROP 3 LASTPIN (2450 3750) SIG_NAME M_D_CPU0_SA_DQS_DP<6>
J 0
(2460 3760);
DISPLAY 0.659574 (2460 3760);
PAINT MONO (2460 3760);
DISPLAY INVISIBLE (2460 3760);
FORCEPROP 1 LASTPIN (2450 3750) BN 6
J 0
(2438 3758);
DISPLAY 0.680851 (2438 3758);
PAINT GREEN (2438 3758);
FORCEPROP 2 LAST CDS_LIB standard
J 0
(2500 3750);
DISPLAY INVISIBLE (2500 3750);
FORCEPROP 1 LAST BODY_TYPE PLUMBING
J 0
(2500 3800);
DISPLAY 0.872340 (2500 3800);
PAINT GREEN (2500 3800);
DISPLAY INVISIBLE (2500 3800);
FORCEPROP 1 LAST HDL_TAP TRUE
J 0
(2825 3625);
DISPLAY 0.872340 (2825 3625);
DISPLAY INVISIBLE (2825 3625);
FORCEPROP 1 LAST PATH I154
J 0
(2498 3750);
DISPLAY 0.872340 (2498 3750);
PAINT GREEN (2498 3750);
DISPLAY INVISIBLE (2498 3750);
FORCEADD TAP..1
(2500 3850);
FORCEPROP 3 LASTPIN (2450 3850) SIG_NAME M_D_CPU0_SA_DQS_DP<7>
J 0
(2460 3860);
DISPLAY 0.659574 (2460 3860);
PAINT MONO (2460 3860);
DISPLAY INVISIBLE (2460 3860);
FORCEPROP 1 LASTPIN (2450 3850) BN 7
J 0
(2438 3858);
DISPLAY 0.680851 (2438 3858);
PAINT GREEN (2438 3858);
FORCEPROP 2 LAST CDS_LIB standard
J 0
(2500 3850);
DISPLAY INVISIBLE (2500 3850);
FORCEPROP 1 LAST BODY_TYPE PLUMBING
J 0
(2500 3900);
DISPLAY 0.872340 (2500 3900);
PAINT GREEN (2500 3900);
DISPLAY INVISIBLE (2500 3900);
FORCEPROP 1 LAST HDL_TAP TRUE
J 0
(2825 3725);
DISPLAY 0.872340 (2825 3725);
DISPLAY INVISIBLE (2825 3725);
FORCEPROP 1 LAST PATH I155
J 0
(2498 3850);
DISPLAY 0.872340 (2498 3850);
PAINT GREEN (2498 3850);
DISPLAY INVISIBLE (2498 3850);
FORCEADD TAP..1
(2500 3950);
FORCEPROP 3 LASTPIN (2450 3950) SIG_NAME M_D_CPU0_SA_DQS_DP<8>
J 0
(2460 3960);
DISPLAY 0.659574 (2460 3960);
PAINT MONO (2460 3960);
DISPLAY INVISIBLE (2460 3960);
FORCEPROP 1 LASTPIN (2450 3950) BN 8
J 0
(2438 3958);
DISPLAY 0.680851 (2438 3958);
PAINT GREEN (2438 3958);
FORCEPROP 2 LAST CDS_LIB standard
J 0
(2500 3950);
DISPLAY INVISIBLE (2500 3950);
FORCEPROP 1 LAST BODY_TYPE PLUMBING
J 0
(2500 4000);
DISPLAY 0.872340 (2500 4000);
PAINT GREEN (2500 4000);
DISPLAY INVISIBLE (2500 4000);
FORCEPROP 1 LAST HDL_TAP TRUE
J 0
(2825 3825);
DISPLAY 0.872340 (2825 3825);
DISPLAY INVISIBLE (2825 3825);
FORCEPROP 1 LAST PATH I156
J 0
(2498 3950);
DISPLAY 0.872340 (2498 3950);
PAINT GREEN (2498 3950);
DISPLAY INVISIBLE (2498 3950);
FORCEADD TAP..1
(2675 3100);
FORCEPROP 3 LASTPIN (2625 3100) SIG_NAME M_D_CPU0_SA_DQS_DN<0>
J 0
(2635 3110);
DISPLAY 0.659574 (2635 3110);
PAINT MONO (2635 3110);
DISPLAY INVISIBLE (2635 3110);
FORCEPROP 1 LASTPIN (2625 3100) BN 0
J 0
(2613 3108);
DISPLAY 0.680851 (2613 3108);
PAINT GREEN (2613 3108);
FORCEPROP 2 LAST CDS_LIB standard
J 0
(2675 3100);
PAINT MONO (2675 3100);
DISPLAY INVISIBLE (2675 3100);
FORCEPROP 1 LAST BODY_TYPE PLUMBING
J 0
(2675 3150);
DISPLAY 0.872340 (2675 3150);
PAINT GREEN (2675 3150);
DISPLAY INVISIBLE (2675 3150);
FORCEPROP 1 LAST HDL_TAP TRUE
J 0
(3000 2975);
DISPLAY 0.872340 (3000 2975);
DISPLAY INVISIBLE (3000 2975);
FORCEPROP 1 LAST PATH I157
J 0
(2673 3100);
DISPLAY 0.872340 (2673 3100);
PAINT GREEN (2673 3100);
DISPLAY INVISIBLE (2673 3100);
FORCEADD TAP..1
(2675 3200);
FORCEPROP 3 LASTPIN (2625 3200) SIG_NAME M_D_CPU0_SA_DQS_DN<1>
J 0
(2635 3210);
DISPLAY 0.659574 (2635 3210);
PAINT MONO (2635 3210);
DISPLAY INVISIBLE (2635 3210);
FORCEPROP 1 LASTPIN (2625 3200) BN 1
J 0
(2613 3208);
DISPLAY 0.680851 (2613 3208);
PAINT GREEN (2613 3208);
FORCEPROP 2 LAST CDS_LIB standard
J 0
(2675 3200);
DISPLAY INVISIBLE (2675 3200);
FORCEPROP 1 LAST BODY_TYPE PLUMBING
J 0
(2675 3250);
DISPLAY 0.872340 (2675 3250);
PAINT GREEN (2675 3250);
DISPLAY INVISIBLE (2675 3250);
FORCEPROP 1 LAST HDL_TAP TRUE
J 0
(3000 3075);
DISPLAY 0.872340 (3000 3075);
DISPLAY INVISIBLE (3000 3075);
FORCEPROP 1 LAST PATH I158
J 0
(2673 3200);
DISPLAY 0.872340 (2673 3200);
PAINT GREEN (2673 3200);
DISPLAY INVISIBLE (2673 3200);
FORCEADD TAP..1
(2675 3300);
FORCEPROP 3 LASTPIN (2625 3300) SIG_NAME M_D_CPU0_SA_DQS_DN<2>
J 0
(2635 3310);
DISPLAY 0.659574 (2635 3310);
PAINT MONO (2635 3310);
DISPLAY INVISIBLE (2635 3310);
FORCEPROP 1 LASTPIN (2625 3300) BN 2
J 0
(2613 3308);
DISPLAY 0.680851 (2613 3308);
PAINT GREEN (2613 3308);
FORCEPROP 2 LAST CDS_LIB standard
J 0
(2675 3300);
DISPLAY INVISIBLE (2675 3300);
FORCEPROP 1 LAST BODY_TYPE PLUMBING
J 0
(2675 3350);
DISPLAY 0.872340 (2675 3350);
PAINT GREEN (2675 3350);
DISPLAY INVISIBLE (2675 3350);
FORCEPROP 1 LAST HDL_TAP TRUE
J 0
(3000 3175);
DISPLAY 0.872340 (3000 3175);
DISPLAY INVISIBLE (3000 3175);
FORCEPROP 1 LAST PATH I159
J 0
(2673 3300);
DISPLAY 0.872340 (2673 3300);
PAINT GREEN (2673 3300);
DISPLAY INVISIBLE (2673 3300);
FORCEADD OFFPAGE..3
R 2
(-2825 2675);
FORCEPROP 2 LAST $XR1 89 
J 0
(-3164 2675);
DISPLAY 0.638298 (-3164 2675);
PAINT MONO (-3164 2675);
FORCEPROP 2 LAST $XR0 23 
J 0
(-3074 2675);
DISPLAY 0.638298 (-3074 2675);
PAINT MONO (-3074 2675);
FORCEPROP 2 LAST CDS_LIB standard
J 0
(-2825 2675);
PAINT MONO (-2825 2675);
DISPLAY INVISIBLE (-2825 2675);
FORCEPROP 1 LAST OFFPAGE TRUE
J 2
(-3150 2550);
DISPLAY 0.872340 (-3150 2550);
DISPLAY INVISIBLE (-3150 2550);
FORCEPROP 1 LAST COMMENT_BODY TRUE
J 2
(-2775 2575);
DISPLAY 0.872340 (-2775 2575);
PAINT GREEN (-2775 2575);
DISPLAY INVISIBLE (-2775 2575);
FORCEPROP 2 LAST PATH I16
J 0
(-2775 2750);
DISPLAY 1.021277 (-2775 2750);
DISPLAY INVISIBLE (-2775 2750);
FORCEADD TAP..1
(2675 3400);
FORCEPROP 3 LASTPIN (2625 3400) SIG_NAME M_D_CPU0_SA_DQS_DN<3>
J 0
(2635 3410);
DISPLAY 0.659574 (2635 3410);
PAINT MONO (2635 3410);
DISPLAY INVISIBLE (2635 3410);
FORCEPROP 1 LASTPIN (2625 3400) BN 3
J 0
(2613 3408);
DISPLAY 0.680851 (2613 3408);
PAINT GREEN (2613 3408);
FORCEPROP 2 LAST CDS_LIB standard
J 0
(2675 3400);
PAINT MONO (2675 3400);
DISPLAY INVISIBLE (2675 3400);
FORCEPROP 1 LAST BODY_TYPE PLUMBING
J 0
(2675 3450);
DISPLAY 0.872340 (2675 3450);
PAINT GREEN (2675 3450);
DISPLAY INVISIBLE (2675 3450);
FORCEPROP 1 LAST HDL_TAP TRUE
J 0
(3000 3275);
DISPLAY 0.872340 (3000 3275);
DISPLAY INVISIBLE (3000 3275);
FORCEPROP 1 LAST PATH I160
J 0
(2673 3400);
DISPLAY 0.872340 (2673 3400);
PAINT GREEN (2673 3400);
DISPLAY INVISIBLE (2673 3400);
FORCEADD TAP..1
(2675 3600);
FORCEPROP 3 LASTPIN (2625 3600) SIG_NAME M_D_CPU0_SA_DQS_DN<5>
J 0
(2635 3610);
DISPLAY 0.659574 (2635 3610);
PAINT MONO (2635 3610);
DISPLAY INVISIBLE (2635 3610);
FORCEPROP 1 LASTPIN (2625 3600) BN 5
J 0
(2613 3608);
DISPLAY 0.680851 (2613 3608);
PAINT GREEN (2613 3608);
FORCEPROP 2 LAST CDS_LIB standard
J 0
(2675 3600);
DISPLAY INVISIBLE (2675 3600);
FORCEPROP 1 LAST BODY_TYPE PLUMBING
J 0
(2675 3650);
DISPLAY 0.872340 (2675 3650);
PAINT GREEN (2675 3650);
DISPLAY INVISIBLE (2675 3650);
FORCEPROP 1 LAST HDL_TAP TRUE
J 0
(3000 3475);
DISPLAY 0.872340 (3000 3475);
DISPLAY INVISIBLE (3000 3475);
FORCEPROP 1 LAST PATH I161
J 0
(2673 3600);
DISPLAY 0.872340 (2673 3600);
PAINT GREEN (2673 3600);
DISPLAY INVISIBLE (2673 3600);
FORCEADD TAP..1
(2675 3500);
FORCEPROP 3 LASTPIN (2625 3500) SIG_NAME M_D_CPU0_SA_DQS_DN<4>
J 0
(2635 3510);
DISPLAY 0.659574 (2635 3510);
PAINT MONO (2635 3510);
DISPLAY INVISIBLE (2635 3510);
FORCEPROP 1 LASTPIN (2625 3500) BN 4
J 0
(2613 3508);
DISPLAY 0.680851 (2613 3508);
PAINT GREEN (2613 3508);
FORCEPROP 2 LAST CDS_LIB standard
J 0
(2675 3500);
PAINT MONO (2675 3500);
DISPLAY INVISIBLE (2675 3500);
FORCEPROP 1 LAST BODY_TYPE PLUMBING
J 0
(2675 3550);
DISPLAY 0.872340 (2675 3550);
PAINT GREEN (2675 3550);
DISPLAY INVISIBLE (2675 3550);
FORCEPROP 1 LAST HDL_TAP TRUE
J 0
(3000 3375);
DISPLAY 0.872340 (3000 3375);
DISPLAY INVISIBLE (3000 3375);
FORCEPROP 1 LAST PATH I162
J 0
(2673 3500);
DISPLAY 0.872340 (2673 3500);
PAINT GREEN (2673 3500);
DISPLAY INVISIBLE (2673 3500);
FORCEADD TAP..1
(2675 3700);
FORCEPROP 3 LASTPIN (2625 3700) SIG_NAME M_D_CPU0_SA_DQS_DN<6>
J 0
(2635 3710);
DISPLAY 0.659574 (2635 3710);
PAINT MONO (2635 3710);
DISPLAY INVISIBLE (2635 3710);
FORCEPROP 1 LASTPIN (2625 3700) BN 6
J 0
(2613 3708);
DISPLAY 0.680851 (2613 3708);
PAINT GREEN (2613 3708);
FORCEPROP 2 LAST CDS_LIB standard
J 0
(2675 3700);
DISPLAY INVISIBLE (2675 3700);
FORCEPROP 1 LAST BODY_TYPE PLUMBING
J 0
(2675 3750);
DISPLAY 0.872340 (2675 3750);
PAINT GREEN (2675 3750);
DISPLAY INVISIBLE (2675 3750);
FORCEPROP 1 LAST HDL_TAP TRUE
J 0
(3000 3575);
DISPLAY 0.872340 (3000 3575);
DISPLAY INVISIBLE (3000 3575);
FORCEPROP 1 LAST PATH I163
J 0
(2673 3700);
DISPLAY 0.872340 (2673 3700);
PAINT GREEN (2673 3700);
DISPLAY INVISIBLE (2673 3700);
FORCEADD TAP..1
(2675 3800);
FORCEPROP 3 LASTPIN (2625 3800) SIG_NAME M_D_CPU0_SA_DQS_DN<7>
J 0
(2635 3810);
DISPLAY 0.659574 (2635 3810);
PAINT MONO (2635 3810);
DISPLAY INVISIBLE (2635 3810);
FORCEPROP 1 LASTPIN (2625 3800) BN 7
J 0
(2613 3808);
DISPLAY 0.680851 (2613 3808);
PAINT GREEN (2613 3808);
FORCEPROP 2 LAST CDS_LIB standard
J 0
(2675 3800);
DISPLAY INVISIBLE (2675 3800);
FORCEPROP 1 LAST BODY_TYPE PLUMBING
J 0
(2675 3850);
DISPLAY 0.872340 (2675 3850);
PAINT GREEN (2675 3850);
DISPLAY INVISIBLE (2675 3850);
FORCEPROP 1 LAST HDL_TAP TRUE
J 0
(3000 3675);
DISPLAY 0.872340 (3000 3675);
DISPLAY INVISIBLE (3000 3675);
FORCEPROP 1 LAST PATH I164
J 0
(2673 3800);
DISPLAY 0.872340 (2673 3800);
PAINT GREEN (2673 3800);
DISPLAY INVISIBLE (2673 3800);
FORCEADD TAP..1
(2675 3900);
FORCEPROP 3 LASTPIN (2625 3900) SIG_NAME M_D_CPU0_SA_DQS_DN<8>
J 0
(2635 3910);
DISPLAY 0.659574 (2635 3910);
PAINT MONO (2635 3910);
DISPLAY INVISIBLE (2635 3910);
FORCEPROP 1 LASTPIN (2625 3900) BN 8
J 0
(2613 3908);
DISPLAY 0.680851 (2613 3908);
PAINT GREEN (2613 3908);
FORCEPROP 2 LAST CDS_LIB standard
J 0
(2675 3900);
DISPLAY INVISIBLE (2675 3900);
FORCEPROP 1 LAST BODY_TYPE PLUMBING
J 0
(2675 3950);
DISPLAY 0.872340 (2675 3950);
PAINT GREEN (2675 3950);
DISPLAY INVISIBLE (2675 3950);
FORCEPROP 1 LAST HDL_TAP TRUE
J 0
(3000 3775);
DISPLAY 0.872340 (3000 3775);
DISPLAY INVISIBLE (3000 3775);
FORCEPROP 1 LAST PATH I165
J 0
(2673 3900);
DISPLAY 0.872340 (2673 3900);
PAINT GREEN (2673 3900);
DISPLAY INVISIBLE (2673 3900);
FORCEADD Q_CAP..1
(3100 175);
FORCEPROP 1 LAST PART_NUMBER CH6103KEA00
J 0
(3150 25);
DISPLAY 0.978723 (3150 25);
DISPLAY INVISIBLE (3150 25);
FORCEPROP 1 LAST MATERIAL X6S
J 0
(3150 75);
DISPLAY 0.978723 (3150 75);
FORCEPROP 1 LAST PACK_TYPE C0805
J 0
(3150 -25);
DISPLAY 0.978723 (3150 -25);
FORCEPROP 1 LAST VALUE 10UF
J 0
(3150 225);
DISPLAY 0.978723 (3150 225);
FORCEPROP 1 LAST TOLERANCE 10%
J 0
(3150 125);
DISPLAY 0.978723 (3150 125);
FORCEPROP 1 LAST VOLTAGE 16V
J 0
(3150 175);
DISPLAY 0.978723 (3150 175);
FORCEPROP 1 LAST $LOCATION C22
J 0
(3150 275);
DISPLAY 0.978723 (3150 275);
FORCEPROP 1 LASTPIN (3100 275) $PN 1
J 0
(3110 255);
DISPLAY 0.787234 (3110 255);
FORCEPROP 1 LASTPIN (3100 75) $PN 2
J 0
(3110 55);
DISPLAY 0.787234 (3110 55);
FORCEPROP 2 LAST CDS_LIB pure_quanta
J 0
(3100 175);
PAINT MONO (3100 175);
DISPLAY INVISIBLE (3100 175);
FORCEPROP 2 LAST CDS_LOCATION C22
J 0
(3150 375);
DISPLAY 1.021277 (3150 375);
DISPLAY INVISIBLE (3150 375);
FORCEPROP 2 LAST $SEC 1
J 0
(3150 375);
DISPLAY 0.680851 (3150 375);
PAINT MONO (3150 375);
DISPLAY INVISIBLE (3150 375);
FORCEPROP 2 LAST CDS_SEC 1
J 0
(3150 375);
DISPLAY 1.021277 (3150 375);
DISPLAY INVISIBLE (3150 375);
FORCEPROP 1 LAST PATH I166
J 0
(3150 325);
DISPLAY 0.978723 (3150 325);
PAINT WHITE (3150 325);
DISPLAY INVISIBLE (3150 325);
FORCEADD UNIVERSAL_GND..1
(4175 350);
FORCEPROP 3 LASTPIN (4175 400) SIG_NAME GND\g
J 0
(4185 410);
DISPLAY 0.659574 (4185 410);
PAINT MONO (4185 410);
DISPLAY INVISIBLE (4185 410);
FORCEPROP 2 LAST CDS_LIB logical_power
J 0
(4175 350);
PAINT MONO (4175 350);
DISPLAY INVISIBLE (4175 350);
FORCEPROP 1 LAST HDL_POWER GND
J 1
(4200 275);
DISPLAY 0.872340 (4200 275);
PAINT GREEN (4200 275);
DISPLAY INVISIBLE (4200 275);
FORCEPROP 1 LAST PATH I167
J 0
(4250 350);
DISPLAY 0.872340 (4250 350);
PAINT AQUA (4250 350);
DISPLAY INVISIBLE (4250 350);
FORCEADD SCONN288_ADR50017P130CC..3
(5025 2425);
FORCEPROP 1 LAST PART_NUMBER DFHST8FS461
J 0
(4570 4349);
DISPLAY 0.723404 (4570 4349);
PAINT GREEN (4570 4349);
DISPLAY INVISIBLE (4570 4349);
FORCEPROP 2 LAST VALUE SCONN288_ADR50017-P130CC
J 0
(4575 4450);
DISPLAY 1.021277 (4575 4450);
FORCEPROP 2 LAST PART_TYPE SMLF
J 0
(4575 4500);
DISPLAY 1.021277 (4575 4500);
FORCEPROP 1 LAST MATERIAL IO
J 0
(4570 4222);
DISPLAY 0.723404 (4570 4222);
PAINT GREEN (4570 4222);
FORCEPROP 1 LAST $LOCATION J7
J 0
(4575 4400);
DISPLAY 0.723404 (4575 4400);
PAINT GREEN (4575 4400);
FORCEPROP 0 LASTPIN (5625 800) $PN G1
J 0
(5635 810);
DISPLAY 0.680851 (5635 810);
PAINT MONO (5635 810);
FORCEPROP 0 LASTPIN (5625 750) $PN G2
J 0
(5635 760);
DISPLAY 0.680851 (5635 760);
PAINT MONO (5635 760);
FORCEPROP 0 LASTPIN (5625 700) $PN G3
J 0
(5635 710);
DISPLAY 0.680851 (5635 710);
PAINT MONO (5635 710);
FORCEPROP 0 LASTPIN (4425 3950) $PN 1
J 2
(4415 3960);
DISPLAY 0.680851 (4415 3960);
PAINT MONO (4415 3960);
FORCEPROP 0 LASTPIN (4425 4000) $PN 145
J 2
(4415 4010);
DISPLAY 0.680851 (4415 4010);
PAINT MONO (4415 4010);
FORCEPROP 0 LASTPIN (4425 4050) $PN 146
J 2
(4415 4060);
DISPLAY 0.680851 (4415 4060);
PAINT MONO (4415 4060);
FORCEPROP 0 LASTPIN (5625 900) $PN 6
J 0
(5635 910);
DISPLAY 0.680851 (5635 910);
PAINT MONO (5635 910);
FORCEPROP 0 LASTPIN (5625 950) $PN 8
J 0
(5635 960);
DISPLAY 0.680851 (5635 960);
PAINT MONO (5635 960);
FORCEPROP 0 LASTPIN (5625 1000) $PN 10
J 0
(5635 1010);
DISPLAY 0.680851 (5635 1010);
PAINT MONO (5635 1010);
FORCEPROP 0 LASTPIN (5625 1050) $PN 13
J 0
(5635 1060);
DISPLAY 0.680851 (5635 1060);
PAINT MONO (5635 1060);
FORCEPROP 0 LASTPIN (5625 1100) $PN 15
J 0
(5635 1110);
DISPLAY 0.680851 (5635 1110);
PAINT MONO (5635 1110);
FORCEPROP 0 LASTPIN (5625 1150) $PN 17
J 0
(5635 1160);
DISPLAY 0.680851 (5635 1160);
PAINT MONO (5635 1160);
FORCEPROP 0 LASTPIN (5625 1200) $PN 19
J 0
(5635 1210);
DISPLAY 0.680851 (5635 1210);
PAINT MONO (5635 1210);
FORCEPROP 0 LASTPIN (5625 1250) $PN 21
J 0
(5635 1260);
DISPLAY 0.680851 (5635 1260);
PAINT MONO (5635 1260);
FORCEPROP 0 LASTPIN (5625 1300) $PN 24
J 0
(5635 1310);
DISPLAY 0.680851 (5635 1310);
PAINT MONO (5635 1310);
FORCEPROP 0 LASTPIN (5625 1350) $PN 26
J 0
(5635 1360);
DISPLAY 0.680851 (5635 1360);
PAINT MONO (5635 1360);
FORCEPROP 0 LASTPIN (5625 1400) $PN 28
J 0
(5635 1410);
DISPLAY 0.680851 (5635 1410);
PAINT MONO (5635 1410);
FORCEPROP 0 LASTPIN (5625 1450) $PN 30
J 0
(5635 1460);
DISPLAY 0.680851 (5635 1460);
PAINT MONO (5635 1460);
FORCEPROP 0 LASTPIN (5625 1500) $PN 32
J 0
(5635 1510);
DISPLAY 0.680851 (5635 1510);
PAINT MONO (5635 1510);
FORCEPROP 0 LASTPIN (5625 1550) $PN 35
J 0
(5635 1560);
DISPLAY 0.680851 (5635 1560);
PAINT MONO (5635 1560);
FORCEPROP 0 LASTPIN (5625 1600) $PN 37
J 0
(5635 1610);
DISPLAY 0.680851 (5635 1610);
PAINT MONO (5635 1610);
FORCEPROP 0 LASTPIN (5625 1650) $PN 39
J 0
(5635 1660);
DISPLAY 0.680851 (5635 1660);
PAINT MONO (5635 1660);
FORCEPROP 0 LASTPIN (5625 1700) $PN 41
J 0
(5635 1710);
DISPLAY 0.680851 (5635 1710);
PAINT MONO (5635 1710);
FORCEPROP 0 LASTPIN (5625 1750) $PN 43
J 0
(5635 1760);
DISPLAY 0.680851 (5635 1760);
PAINT MONO (5635 1760);
FORCEPROP 0 LASTPIN (5625 1800) $PN 46
J 0
(5635 1810);
DISPLAY 0.680851 (5635 1810);
PAINT MONO (5635 1810);
FORCEPROP 0 LASTPIN (5625 1850) $PN 48
J 0
(5635 1860);
DISPLAY 0.680851 (5635 1860);
PAINT MONO (5635 1860);
FORCEPROP 0 LASTPIN (5625 1900) $PN 50
J 0
(5635 1910);
DISPLAY 0.680851 (5635 1910);
PAINT MONO (5635 1910);
FORCEPROP 0 LASTPIN (5625 1950) $PN 52
J 0
(5635 1960);
DISPLAY 0.680851 (5635 1960);
PAINT MONO (5635 1960);
FORCEPROP 0 LASTPIN (5625 2000) $PN 54
J 0
(5635 2010);
DISPLAY 0.680851 (5635 2010);
PAINT MONO (5635 2010);
FORCEPROP 0 LASTPIN (5625 2050) $PN 57
J 0
(5635 2060);
DISPLAY 0.680851 (5635 2060);
PAINT MONO (5635 2060);
FORCEPROP 0 LASTPIN (5625 2100) $PN 59
J 0
(5635 2110);
DISPLAY 0.680851 (5635 2110);
PAINT MONO (5635 2110);
FORCEPROP 0 LASTPIN (5625 2150) $PN 61
J 0
(5635 2160);
DISPLAY 0.680851 (5635 2160);
PAINT MONO (5635 2160);
FORCEPROP 0 LASTPIN (5625 2200) $PN 63
J 0
(5635 2210);
DISPLAY 0.680851 (5635 2210);
PAINT MONO (5635 2210);
FORCEPROP 0 LASTPIN (5625 2250) $PN 65
J 0
(5635 2260);
DISPLAY 0.680851 (5635 2260);
PAINT MONO (5635 2260);
FORCEPROP 0 LASTPIN (5625 2300) $PN 67
J 0
(5635 2310);
DISPLAY 0.680851 (5635 2310);
PAINT MONO (5635 2310);
FORCEPROP 0 LASTPIN (5625 2350) $PN 69
J 0
(5635 2360);
DISPLAY 0.680851 (5635 2360);
PAINT MONO (5635 2360);
FORCEPROP 0 LASTPIN (5625 2400) $PN 71
J 0
(5635 2410);
DISPLAY 0.680851 (5635 2410);
PAINT MONO (5635 2410);
FORCEPROP 0 LASTPIN (5625 2450) $PN 73
J 0
(5635 2460);
DISPLAY 0.680851 (5635 2460);
PAINT MONO (5635 2460);
FORCEPROP 0 LASTPIN (5625 2500) $PN 75
J 0
(5635 2510);
DISPLAY 0.680851 (5635 2510);
PAINT MONO (5635 2510);
FORCEPROP 0 LASTPIN (5625 2550) $PN 77
J 0
(5635 2560);
DISPLAY 0.680851 (5635 2560);
PAINT MONO (5635 2560);
FORCEPROP 0 LASTPIN (5625 2600) $PN 79
J 0
(5635 2610);
DISPLAY 0.680851 (5635 2610);
PAINT MONO (5635 2610);
FORCEPROP 0 LASTPIN (5625 2650) $PN 81
J 0
(5635 2660);
DISPLAY 0.680851 (5635 2660);
PAINT MONO (5635 2660);
FORCEPROP 0 LASTPIN (5625 2700) $PN 83
J 0
(5635 2710);
DISPLAY 0.680851 (5635 2710);
PAINT MONO (5635 2710);
FORCEPROP 0 LASTPIN (5625 2750) $PN 85
J 0
(5635 2760);
DISPLAY 0.680851 (5635 2760);
PAINT MONO (5635 2760);
FORCEPROP 0 LASTPIN (5625 2800) $PN 88
J 0
(5635 2810);
DISPLAY 0.680851 (5635 2810);
PAINT MONO (5635 2810);
FORCEPROP 0 LASTPIN (5625 2850) $PN 90
J 0
(5635 2860);
DISPLAY 0.680851 (5635 2860);
PAINT MONO (5635 2860);
FORCEPROP 0 LASTPIN (5625 2900) $PN 92
J 0
(5635 2910);
DISPLAY 0.680851 (5635 2910);
PAINT MONO (5635 2910);
FORCEPROP 0 LASTPIN (5625 2950) $PN 95
J 0
(5635 2960);
DISPLAY 0.680851 (5635 2960);
PAINT MONO (5635 2960);
FORCEPROP 0 LASTPIN (5625 3000) $PN 97
J 0
(5635 3010);
DISPLAY 0.680851 (5635 3010);
PAINT MONO (5635 3010);
FORCEPROP 0 LASTPIN (5625 3050) $PN 99
J 0
(5635 3060);
DISPLAY 0.680851 (5635 3060);
PAINT MONO (5635 3060);
FORCEPROP 0 LASTPIN (5625 3100) $PN 101
J 0
(5635 3110);
DISPLAY 0.680851 (5635 3110);
PAINT MONO (5635 3110);
FORCEPROP 0 LASTPIN (5625 3150) $PN 103
J 0
(5635 3160);
DISPLAY 0.680851 (5635 3160);
PAINT MONO (5635 3160);
FORCEPROP 0 LASTPIN (5625 3200) $PN 106
J 0
(5635 3210);
DISPLAY 0.680851 (5635 3210);
PAINT MONO (5635 3210);
FORCEPROP 0 LASTPIN (5625 3250) $PN 108
J 0
(5635 3260);
DISPLAY 0.680851 (5635 3260);
PAINT MONO (5635 3260);
FORCEPROP 0 LASTPIN (5625 3300) $PN 110
J 0
(5635 3310);
DISPLAY 0.680851 (5635 3310);
PAINT MONO (5635 3310);
FORCEPROP 0 LASTPIN (5625 3350) $PN 112
J 0
(5635 3360);
DISPLAY 0.680851 (5635 3360);
PAINT MONO (5635 3360);
FORCEPROP 0 LASTPIN (5625 3400) $PN 114
J 0
(5635 3410);
DISPLAY 0.680851 (5635 3410);
PAINT MONO (5635 3410);
FORCEPROP 0 LASTPIN (5625 3450) $PN 117
J 0
(5635 3460);
DISPLAY 0.680851 (5635 3460);
PAINT MONO (5635 3460);
FORCEPROP 0 LASTPIN (5625 3500) $PN 119
J 0
(5635 3510);
DISPLAY 0.680851 (5635 3510);
PAINT MONO (5635 3510);
FORCEPROP 0 LASTPIN (5625 3550) $PN 121
J 0
(5635 3560);
DISPLAY 0.680851 (5635 3560);
PAINT MONO (5635 3560);
FORCEPROP 0 LASTPIN (5625 3600) $PN 123
J 0
(5635 3610);
DISPLAY 0.680851 (5635 3610);
PAINT MONO (5635 3610);
FORCEPROP 0 LASTPIN (5625 3650) $PN 125
J 0
(5635 3660);
DISPLAY 0.680851 (5635 3660);
PAINT MONO (5635 3660);
FORCEPROP 0 LASTPIN (5625 3700) $PN 128
J 0
(5635 3710);
DISPLAY 0.680851 (5635 3710);
PAINT MONO (5635 3710);
FORCEPROP 0 LASTPIN (5625 3750) $PN 130
J 0
(5635 3760);
DISPLAY 0.680851 (5635 3760);
PAINT MONO (5635 3760);
FORCEPROP 0 LASTPIN (5625 3800) $PN 132
J 0
(5635 3810);
DISPLAY 0.680851 (5635 3810);
PAINT MONO (5635 3810);
FORCEPROP 0 LASTPIN (5625 3850) $PN 134
J 0
(5635 3860);
DISPLAY 0.680851 (5635 3860);
PAINT MONO (5635 3860);
FORCEPROP 0 LASTPIN (5625 3900) $PN 136
J 0
(5635 3910);
DISPLAY 0.680851 (5635 3910);
PAINT MONO (5635 3910);
FORCEPROP 0 LASTPIN (5625 3950) $PN 139
J 0
(5635 3960);
DISPLAY 0.680851 (5635 3960);
PAINT MONO (5635 3960);
FORCEPROP 0 LASTPIN (5625 4000) $PN 141
J 0
(5635 4010);
DISPLAY 0.680851 (5635 4010);
PAINT MONO (5635 4010);
FORCEPROP 0 LASTPIN (5625 4050) $PN 143
J 0
(5635 4060);
DISPLAY 0.680851 (5635 4060);
PAINT MONO (5635 4060);
FORCEPROP 0 LASTPIN (4425 800) $PN 151
J 2
(4415 810);
DISPLAY 0.680851 (4415 810);
PAINT MONO (4415 810);
FORCEPROP 0 LASTPIN (4425 850) $PN 153
J 2
(4415 860);
DISPLAY 0.680851 (4415 860);
PAINT MONO (4415 860);
FORCEPROP 0 LASTPIN (4425 900) $PN 155
J 2
(4415 910);
DISPLAY 0.680851 (4415 910);
PAINT MONO (4415 910);
FORCEPROP 0 LASTPIN (4425 950) $PN 158
J 2
(4415 960);
DISPLAY 0.680851 (4415 960);
PAINT MONO (4415 960);
FORCEPROP 0 LASTPIN (4425 1000) $PN 160
J 2
(4415 1010);
DISPLAY 0.680851 (4415 1010);
PAINT MONO (4415 1010);
FORCEPROP 0 LASTPIN (4425 1050) $PN 162
J 2
(4415 1060);
DISPLAY 0.680851 (4415 1060);
PAINT MONO (4415 1060);
FORCEPROP 0 LASTPIN (4425 1100) $PN 164
J 2
(4415 1110);
DISPLAY 0.680851 (4415 1110);
PAINT MONO (4415 1110);
FORCEPROP 0 LASTPIN (4425 1150) $PN 166
J 2
(4415 1160);
DISPLAY 0.680851 (4415 1160);
PAINT MONO (4415 1160);
FORCEPROP 0 LASTPIN (4425 1200) $PN 169
J 2
(4415 1210);
DISPLAY 0.680851 (4415 1210);
PAINT MONO (4415 1210);
FORCEPROP 0 LASTPIN (4425 1250) $PN 171
J 2
(4415 1260);
DISPLAY 0.680851 (4415 1260);
PAINT MONO (4415 1260);
FORCEPROP 0 LASTPIN (4425 1300) $PN 173
J 2
(4415 1310);
DISPLAY 0.680851 (4415 1310);
PAINT MONO (4415 1310);
FORCEPROP 0 LASTPIN (4425 1350) $PN 175
J 2
(4415 1360);
DISPLAY 0.680851 (4415 1360);
PAINT MONO (4415 1360);
FORCEPROP 0 LASTPIN (4425 1400) $PN 177
J 2
(4415 1410);
DISPLAY 0.680851 (4415 1410);
PAINT MONO (4415 1410);
FORCEPROP 0 LASTPIN (4425 1450) $PN 180
J 2
(4415 1460);
DISPLAY 0.680851 (4415 1460);
PAINT MONO (4415 1460);
FORCEPROP 0 LASTPIN (4425 1500) $PN 182
J 2
(4415 1510);
DISPLAY 0.680851 (4415 1510);
PAINT MONO (4415 1510);
FORCEPROP 0 LASTPIN (4425 1550) $PN 184
J 2
(4415 1560);
DISPLAY 0.680851 (4415 1560);
PAINT MONO (4415 1560);
FORCEPROP 0 LASTPIN (4425 1600) $PN 186
J 2
(4415 1610);
DISPLAY 0.680851 (4415 1610);
PAINT MONO (4415 1610);
FORCEPROP 0 LASTPIN (4425 1650) $PN 188
J 2
(4415 1660);
DISPLAY 0.680851 (4415 1660);
PAINT MONO (4415 1660);
FORCEPROP 0 LASTPIN (4425 1700) $PN 191
J 2
(4415 1710);
DISPLAY 0.680851 (4415 1710);
PAINT MONO (4415 1710);
FORCEPROP 0 LASTPIN (4425 1750) $PN 193
J 2
(4415 1760);
DISPLAY 0.680851 (4415 1760);
PAINT MONO (4415 1760);
FORCEPROP 0 LASTPIN (4425 1800) $PN 195
J 2
(4415 1810);
DISPLAY 0.680851 (4415 1810);
PAINT MONO (4415 1810);
FORCEPROP 0 LASTPIN (4425 1850) $PN 197
J 2
(4415 1860);
DISPLAY 0.680851 (4415 1860);
PAINT MONO (4415 1860);
FORCEPROP 0 LASTPIN (4425 1900) $PN 199
J 2
(4415 1910);
DISPLAY 0.680851 (4415 1910);
PAINT MONO (4415 1910);
FORCEPROP 0 LASTPIN (4425 1950) $PN 202
J 2
(4415 1960);
DISPLAY 0.680851 (4415 1960);
PAINT MONO (4415 1960);
FORCEPROP 0 LASTPIN (4425 2000) $PN 204
J 2
(4415 2010);
DISPLAY 0.680851 (4415 2010);
PAINT MONO (4415 2010);
FORCEPROP 0 LASTPIN (4425 2050) $PN 206
J 2
(4415 2060);
DISPLAY 0.680851 (4415 2060);
PAINT MONO (4415 2060);
FORCEPROP 0 LASTPIN (4425 2100) $PN 208
J 2
(4415 2110);
DISPLAY 0.680851 (4415 2110);
PAINT MONO (4415 2110);
FORCEPROP 0 LASTPIN (4425 2150) $PN 210
J 2
(4415 2160);
DISPLAY 0.680851 (4415 2160);
PAINT MONO (4415 2160);
FORCEPROP 0 LASTPIN (4425 2200) $PN 212
J 2
(4415 2210);
DISPLAY 0.680851 (4415 2210);
PAINT MONO (4415 2210);
FORCEPROP 0 LASTPIN (4425 2250) $PN 214
J 2
(4415 2260);
DISPLAY 0.680851 (4415 2260);
PAINT MONO (4415 2260);
FORCEPROP 0 LASTPIN (4425 2300) $PN 216
J 2
(4415 2310);
DISPLAY 0.680851 (4415 2310);
PAINT MONO (4415 2310);
FORCEPROP 0 LASTPIN (4425 2350) $PN 219
J 2
(4415 2360);
DISPLAY 0.680851 (4415 2360);
PAINT MONO (4415 2360);
FORCEPROP 0 LASTPIN (4425 2400) $PN 222
J 2
(4415 2410);
DISPLAY 0.680851 (4415 2410);
PAINT MONO (4415 2410);
FORCEPROP 0 LASTPIN (4425 2450) $PN 224
J 2
(4415 2460);
DISPLAY 0.680851 (4415 2460);
PAINT MONO (4415 2460);
FORCEPROP 0 LASTPIN (4425 2500) $PN 226
J 2
(4415 2510);
DISPLAY 0.680851 (4415 2510);
PAINT MONO (4415 2510);
FORCEPROP 0 LASTPIN (4425 2550) $PN 228
J 2
(4415 2560);
DISPLAY 0.680851 (4415 2560);
PAINT MONO (4415 2560);
FORCEPROP 0 LASTPIN (4425 2600) $PN 230
J 2
(4415 2610);
DISPLAY 0.680851 (4415 2610);
PAINT MONO (4415 2610);
FORCEPROP 0 LASTPIN (4425 2650) $PN 233
J 2
(4415 2660);
DISPLAY 0.680851 (4415 2660);
PAINT MONO (4415 2660);
FORCEPROP 0 LASTPIN (4425 2700) $PN 235
J 2
(4415 2710);
DISPLAY 0.680851 (4415 2710);
PAINT MONO (4415 2710);
FORCEPROP 0 LASTPIN (4425 2750) $PN 237
J 2
(4415 2760);
DISPLAY 0.680851 (4415 2760);
PAINT MONO (4415 2760);
FORCEPROP 0 LASTPIN (4425 2800) $PN 240
J 2
(4415 2810);
DISPLAY 0.680851 (4415 2810);
PAINT MONO (4415 2810);
FORCEPROP 0 LASTPIN (4425 2850) $PN 242
J 2
(4415 2860);
DISPLAY 0.680851 (4415 2860);
PAINT MONO (4415 2860);
FORCEPROP 0 LASTPIN (4425 2900) $PN 244
J 2
(4415 2910);
DISPLAY 0.680851 (4415 2910);
PAINT MONO (4415 2910);
FORCEPROP 0 LASTPIN (4425 2950) $PN 246
J 2
(4415 2960);
DISPLAY 0.680851 (4415 2960);
PAINT MONO (4415 2960);
FORCEPROP 0 LASTPIN (4425 3000) $PN 248
J 2
(4415 3010);
DISPLAY 0.680851 (4415 3010);
PAINT MONO (4415 3010);
FORCEPROP 0 LASTPIN (4425 3050) $PN 251
J 2
(4415 3060);
DISPLAY 0.680851 (4415 3060);
PAINT MONO (4415 3060);
FORCEPROP 0 LASTPIN (4425 3100) $PN 253
J 2
(4415 3110);
DISPLAY 0.680851 (4415 3110);
PAINT MONO (4415 3110);
FORCEPROP 0 LASTPIN (4425 3150) $PN 255
J 2
(4415 3160);
DISPLAY 0.680851 (4415 3160);
PAINT MONO (4415 3160);
FORCEPROP 0 LASTPIN (4425 3200) $PN 257
J 2
(4415 3210);
DISPLAY 0.680851 (4415 3210);
PAINT MONO (4415 3210);
FORCEPROP 0 LASTPIN (4425 3250) $PN 259
J 2
(4415 3260);
DISPLAY 0.680851 (4415 3260);
PAINT MONO (4415 3260);
FORCEPROP 0 LASTPIN (4425 3300) $PN 262
J 2
(4415 3310);
DISPLAY 0.680851 (4415 3310);
PAINT MONO (4415 3310);
FORCEPROP 0 LASTPIN (4425 3350) $PN 264
J 2
(4415 3360);
DISPLAY 0.680851 (4415 3360);
PAINT MONO (4415 3360);
FORCEPROP 0 LASTPIN (4425 3400) $PN 266
J 2
(4415 3410);
DISPLAY 0.680851 (4415 3410);
PAINT MONO (4415 3410);
FORCEPROP 0 LASTPIN (4425 3450) $PN 268
J 2
(4415 3460);
DISPLAY 0.680851 (4415 3460);
PAINT MONO (4415 3460);
FORCEPROP 0 LASTPIN (4425 3500) $PN 270
J 2
(4415 3510);
DISPLAY 0.680851 (4415 3510);
PAINT MONO (4415 3510);
FORCEPROP 0 LASTPIN (4425 3550) $PN 273
J 2
(4415 3560);
DISPLAY 0.680851 (4415 3560);
PAINT MONO (4415 3560);
FORCEPROP 0 LASTPIN (4425 3600) $PN 275
J 2
(4415 3610);
DISPLAY 0.680851 (4415 3610);
PAINT MONO (4415 3610);
FORCEPROP 0 LASTPIN (4425 3650) $PN 277
J 2
(4415 3660);
DISPLAY 0.680851 (4415 3660);
PAINT MONO (4415 3660);
FORCEPROP 0 LASTPIN (4425 3700) $PN 279
J 2
(4415 3710);
DISPLAY 0.680851 (4415 3710);
PAINT MONO (4415 3710);
FORCEPROP 0 LASTPIN (4425 3750) $PN 281
J 2
(4415 3760);
DISPLAY 0.680851 (4415 3760);
PAINT MONO (4415 3760);
FORCEPROP 0 LASTPIN (4425 3800) $PN 284
J 2
(4415 3810);
DISPLAY 0.680851 (4415 3810);
PAINT MONO (4415 3810);
FORCEPROP 0 LASTPIN (4425 3850) $PN 286
J 2
(4415 3860);
DISPLAY 0.680851 (4415 3860);
PAINT MONO (4415 3860);
FORCEPROP 0 LASTPIN (4425 3900) $PN 288
J 2
(4415 3910);
DISPLAY 0.680851 (4415 3910);
PAINT MONO (4415 3910);
FORCEPROP 2 LAST CDS_LIB pure_quanta
J 0
(5025 2425);
DISPLAY INVISIBLE (5025 2425);
FORCEPROP 1 LAST CDS_LMAN_SYM_OUTLINE -450,1775,450,-1775
J 0
(5025 2425);
DISPLAY 0.468085 (5025 2425);
PAINT GREEN (5025 2425);
DISPLAY INVISIBLE (5025 2425);
FORCEPROP 1 LAST NEEDS_NO_SIZE TRUE
J 0
(5025 2425);
DISPLAY 0.723404 (5025 2425);
PAINT GREEN (5025 2425);
DISPLAY INVISIBLE (5025 2425);
FORCEPROP 2 LAST CDS_LOCATION J7
J 0
(4575 4550);
DISPLAY 1.021277 (4575 4550);
DISPLAY INVISIBLE (4575 4550);
FORCEPROP 0 LAST $SEC 3
J 0
(4575 4550);
DISPLAY 0.680851 (4575 4550);
PAINT MONO (4575 4550);
DISPLAY INVISIBLE (4575 4550);
FORCEPROP 2 LAST CDS_SEC 3
J 0
(4575 4550);
DISPLAY 1.021277 (4575 4550);
DISPLAY INVISIBLE (4575 4550);
FORCEPROP 1 LAST PATH I168
J 0
(5025 2425);
DISPLAY 0.723404 (5025 2425);
PAINT GREEN (5025 2425);
DISPLAY INVISIBLE (5025 2425);
FORCEADD OFFPAGE..2
(3625 2975);
FORCEPROP 2 LAST $XR1 89 
J 0
(3904 2975);
DISPLAY 0.638298 (3904 2975);
PAINT MONO (3904 2975);
FORCEPROP 2 LAST $XR0 23 
J 0
(3814 2975);
DISPLAY 0.638298 (3814 2975);
PAINT MONO (3814 2975);
FORCEPROP 2 LAST CDS_LIB standard
J 0
(3625 2975);
PAINT MONO (3625 2975);
DISPLAY INVISIBLE (3625 2975);
FORCEPROP 1 LAST OFFPAGE TRUE
J 0
(3950 2850);
DISPLAY 1.170213 (3950 2850);
PAINT GREEN (3950 2850);
DISPLAY INVISIBLE (3950 2850);
FORCEPROP 1 LAST COMMENT_BODY TRUE
J 0
(3580 2880);
DISPLAY 1.170213 (3580 2880);
PAINT GREEN (3580 2880);
DISPLAY INVISIBLE (3580 2880);
FORCEPROP 2 LAST PATH I169
J 0
(3800 3050);
DISPLAY 1.021277 (3800 3050);
DISPLAY INVISIBLE (3800 3050);
FORCEADD OFFPAGE..1
(-2825 2900);
FORCEPROP 2 LAST $XR0 23 
J 0
(-3046 2900);
DISPLAY 0.638298 (-3046 2900);
PAINT MONO (-3046 2900);
FORCEPROP 2 LAST CDS_LIB standard
J 0
(-2825 2900);
PAINT MONO (-2825 2900);
DISPLAY INVISIBLE (-2825 2900);
FORCEPROP 1 LAST OFFPAGE TRUE
J 0
(-2500 2775);
DISPLAY 0.872340 (-2500 2775);
DISPLAY INVISIBLE (-2500 2775);
FORCEPROP 1 LAST COMMENT_BODY TRUE
J 0
(-2700 2800);
DISPLAY 0.872340 (-2700 2800);
PAINT GREEN (-2700 2800);
DISPLAY INVISIBLE (-2700 2800);
FORCEPROP 2 LAST PATH I17
J 0
(-2775 2975);
DISPLAY 1.021277 (-2775 2975);
DISPLAY INVISIBLE (-2775 2975);
FORCEADD OFFPAGE..2
(3625 3025);
FORCEPROP 2 LAST $XR1 89 
J 0
(3904 3025);
DISPLAY 0.638298 (3904 3025);
PAINT MONO (3904 3025);
FORCEPROP 2 LAST $XR0 23 
J 0
(3814 3025);
DISPLAY 0.638298 (3814 3025);
PAINT MONO (3814 3025);
FORCEPROP 2 LAST CDS_LIB standard
J 0
(3625 3025);
PAINT MONO (3625 3025);
DISPLAY INVISIBLE (3625 3025);
FORCEPROP 1 LAST OFFPAGE TRUE
J 0
(3950 2900);
DISPLAY 1.170213 (3950 2900);
PAINT GREEN (3950 2900);
DISPLAY INVISIBLE (3950 2900);
FORCEPROP 1 LAST COMMENT_BODY TRUE
J 0
(3580 2930);
DISPLAY 1.170213 (3580 2930);
PAINT GREEN (3580 2930);
DISPLAY INVISIBLE (3580 2930);
FORCEPROP 2 LAST PATH I170
J 0
(3800 3100);
DISPLAY 1.021277 (3800 3100);
DISPLAY INVISIBLE (3800 3100);
FORCEADD OFFPAGE..2
(3625 4025);
FORCEPROP 2 LAST $XR1 89 
J 0
(3904 4025);
DISPLAY 0.638298 (3904 4025);
PAINT MONO (3904 4025);
FORCEPROP 2 LAST $XR0 23 
J 0
(3814 4025);
DISPLAY 0.638298 (3814 4025);
PAINT MONO (3814 4025);
FORCEPROP 2 LAST CDS_LIB standard
J 0
(3625 4025);
PAINT MONO (3625 4025);
DISPLAY INVISIBLE (3625 4025);
FORCEPROP 1 LAST OFFPAGE TRUE
J 0
(3950 3900);
DISPLAY 1.170213 (3950 3900);
PAINT GREEN (3950 3900);
DISPLAY INVISIBLE (3950 3900);
FORCEPROP 1 LAST COMMENT_BODY TRUE
J 0
(3580 3930);
DISPLAY 1.170213 (3580 3930);
PAINT GREEN (3580 3930);
DISPLAY INVISIBLE (3580 3930);
FORCEPROP 2 LAST PATH I171
J 0
(3800 4100);
DISPLAY 1.021277 (3800 4100);
DISPLAY INVISIBLE (3800 4100);
FORCEADD TAP..1
(2500 4050);
FORCEPROP 3 LASTPIN (2450 4050) SIG_NAME M_D_CPU0_SA_DQS_DP<9>
J 0
(2460 4060);
DISPLAY 0.659574 (2460 4060);
PAINT MONO (2460 4060);
DISPLAY INVISIBLE (2460 4060);
FORCEPROP 1 LASTPIN (2450 4050) BN 9
J 0
(2438 4058);
DISPLAY 0.680851 (2438 4058);
PAINT GREEN (2438 4058);
FORCEPROP 2 LAST CDS_LIB standard
J 0
(2500 4050);
DISPLAY INVISIBLE (2500 4050);
FORCEPROP 1 LAST BODY_TYPE PLUMBING
J 0
(2500 4100);
DISPLAY 0.872340 (2500 4100);
PAINT GREEN (2500 4100);
DISPLAY INVISIBLE (2500 4100);
FORCEPROP 1 LAST HDL_TAP TRUE
J 0
(2825 3925);
DISPLAY 0.872340 (2825 3925);
DISPLAY INVISIBLE (2825 3925);
FORCEPROP 1 LAST PATH I172
J 0
(2498 4050);
DISPLAY 0.872340 (2498 4050);
PAINT GREEN (2498 4050);
DISPLAY INVISIBLE (2498 4050);
FORCEADD TAP..1
(2675 4000);
FORCEPROP 3 LASTPIN (2625 4000) SIG_NAME M_D_CPU0_SA_DQS_DN<9>
J 0
(2635 4010);
DISPLAY 0.659574 (2635 4010);
PAINT MONO (2635 4010);
DISPLAY INVISIBLE (2635 4010);
FORCEPROP 1 LASTPIN (2625 4000) BN 9
J 0
(2613 4008);
DISPLAY 0.680851 (2613 4008);
PAINT GREEN (2613 4008);
FORCEPROP 2 LAST CDS_LIB standard
J 0
(2675 4000);
DISPLAY INVISIBLE (2675 4000);
FORCEPROP 1 LAST BODY_TYPE PLUMBING
J 0
(2675 4050);
DISPLAY 0.872340 (2675 4050);
PAINT GREEN (2675 4050);
DISPLAY INVISIBLE (2675 4050);
FORCEPROP 1 LAST HDL_TAP TRUE
J 0
(3000 3875);
DISPLAY 0.872340 (3000 3875);
DISPLAY INVISIBLE (3000 3875);
FORCEPROP 1 LAST PATH I173
J 0
(2673 4000);
DISPLAY 0.872340 (2673 4000);
PAINT GREEN (2673 4000);
DISPLAY INVISIBLE (2673 4000);
FORCEADD OFFPAGE..2
(3625 4075);
FORCEPROP 2 LAST $XR1 89 
J 0
(3904 4075);
DISPLAY 0.638298 (3904 4075);
PAINT MONO (3904 4075);
FORCEPROP 2 LAST $XR0 23 
J 0
(3814 4075);
DISPLAY 0.638298 (3814 4075);
PAINT MONO (3814 4075);
FORCEPROP 2 LAST CDS_LIB standard
J 0
(3625 4075);
PAINT MONO (3625 4075);
DISPLAY INVISIBLE (3625 4075);
FORCEPROP 1 LAST OFFPAGE TRUE
J 0
(3950 3950);
DISPLAY 1.170213 (3950 3950);
PAINT GREEN (3950 3950);
DISPLAY INVISIBLE (3950 3950);
FORCEPROP 1 LAST COMMENT_BODY TRUE
J 0
(3580 3980);
DISPLAY 1.170213 (3580 3980);
PAINT GREEN (3580 3980);
DISPLAY INVISIBLE (3580 3980);
FORCEPROP 2 LAST PATH I174
J 0
(3800 4150);
DISPLAY 1.021277 (3800 4150);
DISPLAY INVISIBLE (3800 4150);
FORCEADD VCC_CORE..1
(4175 4600);
FORCEPROP 3 LASTPIN (4175 4550) SIG_NAME P12V_S3_AUX_CPU0_NVDIMM\g
J 0
(4185 4560);
DISPLAY 0.659574 (4185 4560);
PAINT MONO (4185 4560);
DISPLAY INVISIBLE (4185 4560);
FORCEPROP 1 LAST HDL_POWER P12V_S3_AUX_CPU0_NVDIMM
J 1
(4175 4650);
DISPLAY 1.148936 (4175 4650);
PAINT GREEN (4175 4650);
FORCEPROP 2 LAST CDS_LIB logical_power
J 0
(4175 4600);
PAINT MONO (4175 4600);
DISPLAY INVISIBLE (4175 4600);
FORCEPROP 1 LAST PATH I175
J 0
(4225 4625);
DISPLAY 0.872340 (4225 4625);
PAINT AQUA (4225 4625);
DISPLAY INVISIBLE (4225 4625);
FORCEADD UNIVERSAL_GND..1
(5875 350);
FORCEPROP 3 LASTPIN (5875 400) SIG_NAME GND\g
J 0
(5885 410);
DISPLAY 0.659574 (5885 410);
PAINT MONO (5885 410);
DISPLAY INVISIBLE (5885 410);
FORCEPROP 2 LAST CDS_LIB logical_power
J 0
(5875 350);
PAINT MONO (5875 350);
DISPLAY INVISIBLE (5875 350);
FORCEPROP 1 LAST HDL_POWER GND
J 1
(5900 275);
DISPLAY 0.872340 (5900 275);
PAINT GREEN (5900 275);
DISPLAY INVISIBLE (5900 275);
FORCEPROP 1 LAST PATH I176
J 0
(5950 350);
DISPLAY 0.872340 (5950 350);
PAINT AQUA (5950 350);
DISPLAY INVISIBLE (5950 350);
FORCEADD OFFPAGE..3
R 2
(-2825 1200);
FORCEPROP 2 LAST $XR0 114 
J 0
(-3105 1200);
DISPLAY 0.638298 (-3105 1200);
PAINT MONO (-3105 1200);
FORCEPROP 2 LAST CDS_LIB standard
J 0
(-2825 1200);
PAINT MONO (-2825 1200);
DISPLAY INVISIBLE (-2825 1200);
FORCEPROP 1 LAST OFFPAGE TRUE
J 2
(-3150 1075);
DISPLAY 0.872340 (-3150 1075);
DISPLAY INVISIBLE (-3150 1075);
FORCEPROP 1 LAST COMMENT_BODY TRUE
J 2
(-2775 1100);
DISPLAY 0.872340 (-2775 1100);
PAINT GREEN (-2775 1100);
DISPLAY INVISIBLE (-2775 1100);
FORCEPROP 2 LAST PATH I177
J 0
(-2775 1275);
DISPLAY 1.021277 (-2775 1275);
DISPLAY INVISIBLE (-2775 1275);
FORCEADD SCONN288_ADR50017P130CC..2
(1600 3050);
FORCEPROP 1 LAST PART_NUMBER DFHST8FS461
J 0
(1007 4350);
DISPLAY 0.723404 (1007 4350);
PAINT GREEN (1007 4350);
DISPLAY INVISIBLE (1007 4350);
FORCEPROP 1 LAST MATERIAL IO
J 0
(1007 4223);
DISPLAY 0.723404 (1007 4223);
PAINT GREEN (1007 4223);
FORCEPROP 2 LAST VALUE SCONN288_ADR50017-P130CC
J 0
(1018 4453);
DISPLAY 1.021277 (1018 4453);
FORCEPROP 2 LAST PART_TYPE SMLF
J 0
(1018 4503);
DISPLAY 1.021277 (1018 4503);
FORCEPROP 1 LAST LOCATION J7
J 0
(1000 4400);
DISPLAY 0.723404 (1000 4400);
PAINT GREEN (1000 4400);
FORCEPROP 0 LASTPIN (2350 3100) $PN 12
J 0
(2360 3110);
DISPLAY 0.680851 (2360 3110);
PAINT MONO (2360 3110);
FORCEPROP 0 LASTPIN (2350 3150) $PN 11
J 0
(2360 3160);
DISPLAY 0.680851 (2360 3160);
PAINT MONO (2360 3160);
FORCEPROP 0 LASTPIN (2350 2050) $PN 105
J 0
(2360 2060);
DISPLAY 0.680851 (2360 2060);
PAINT MONO (2360 2060);
FORCEPROP 0 LASTPIN (2350 2100) $PN 104
J 0
(2360 2110);
DISPLAY 0.680851 (2360 2110);
PAINT MONO (2360 2110);
FORCEPROP 0 LASTPIN (2350 3200) $PN 23
J 0
(2360 3210);
DISPLAY 0.680851 (2360 3210);
PAINT MONO (2360 3210);
FORCEPROP 0 LASTPIN (2350 3250) $PN 22
J 0
(2360 3260);
DISPLAY 0.680851 (2360 3260);
PAINT MONO (2360 3260);
FORCEPROP 0 LASTPIN (2350 2150) $PN 116
J 0
(2360 2160);
DISPLAY 0.680851 (2360 2160);
PAINT MONO (2360 2160);
FORCEPROP 0 LASTPIN (2350 2200) $PN 115
J 0
(2360 2210);
DISPLAY 0.680851 (2360 2210);
PAINT MONO (2360 2210);
FORCEPROP 0 LASTPIN (2350 3300) $PN 34
J 0
(2360 3310);
DISPLAY 0.680851 (2360 3310);
PAINT MONO (2360 3310);
FORCEPROP 0 LASTPIN (2350 3350) $PN 33
J 0
(2360 3360);
DISPLAY 0.680851 (2360 3360);
PAINT MONO (2360 3360);
FORCEPROP 0 LASTPIN (2350 2250) $PN 127
J 0
(2360 2260);
DISPLAY 0.680851 (2360 2260);
PAINT MONO (2360 2260);
FORCEPROP 0 LASTPIN (2350 2300) $PN 126
J 0
(2360 2310);
DISPLAY 0.680851 (2360 2310);
PAINT MONO (2360 2310);
FORCEPROP 0 LASTPIN (2350 3400) $PN 45
J 0
(2360 3410);
DISPLAY 0.680851 (2360 3410);
PAINT MONO (2360 3410);
FORCEPROP 0 LASTPIN (2350 3450) $PN 44
J 0
(2360 3460);
DISPLAY 0.680851 (2360 3460);
PAINT MONO (2360 3460);
FORCEPROP 0 LASTPIN (2350 2350) $PN 138
J 0
(2360 2360);
DISPLAY 0.680851 (2360 2360);
PAINT MONO (2360 2360);
FORCEPROP 0 LASTPIN (2350 2400) $PN 137
J 0
(2360 2410);
DISPLAY 0.680851 (2360 2410);
PAINT MONO (2360 2410);
FORCEPROP 0 LASTPIN (2350 3500) $PN 56
J 0
(2360 3510);
DISPLAY 0.680851 (2360 3510);
PAINT MONO (2360 3510);
FORCEPROP 0 LASTPIN (2350 3550) $PN 55
J 0
(2360 3560);
DISPLAY 0.680851 (2360 3560);
PAINT MONO (2360 3560);
FORCEPROP 0 LASTPIN (2350 2450) $PN 238
J 0
(2360 2460);
DISPLAY 0.680851 (2360 2460);
PAINT MONO (2360 2460);
FORCEPROP 0 LASTPIN (2350 2500) $PN 239
J 0
(2360 2510);
DISPLAY 0.680851 (2360 2510);
PAINT MONO (2360 2510);
FORCEPROP 0 LASTPIN (2350 3600) $PN 156
J 0
(2360 3610);
DISPLAY 0.680851 (2360 3610);
PAINT MONO (2360 3610);
FORCEPROP 0 LASTPIN (2350 3650) $PN 157
J 0
(2360 3660);
DISPLAY 0.680851 (2360 3660);
PAINT MONO (2360 3660);
FORCEPROP 0 LASTPIN (2350 2550) $PN 249
J 0
(2360 2560);
DISPLAY 0.680851 (2360 2560);
PAINT MONO (2360 2560);
FORCEPROP 0 LASTPIN (2350 2600) $PN 250
J 0
(2360 2610);
DISPLAY 0.680851 (2360 2610);
PAINT MONO (2360 2610);
FORCEPROP 0 LASTPIN (2350 3700) $PN 167
J 0
(2360 3710);
DISPLAY 0.680851 (2360 3710);
PAINT MONO (2360 3710);
FORCEPROP 0 LASTPIN (2350 3750) $PN 168
J 0
(2360 3760);
DISPLAY 0.680851 (2360 3760);
PAINT MONO (2360 3760);
FORCEPROP 0 LASTPIN (2350 2650) $PN 260
J 0
(2360 2660);
DISPLAY 0.680851 (2360 2660);
PAINT MONO (2360 2660);
FORCEPROP 0 LASTPIN (2350 2700) $PN 261
J 0
(2360 2710);
DISPLAY 0.680851 (2360 2710);
PAINT MONO (2360 2710);
FORCEPROP 0 LASTPIN (2350 3800) $PN 178
J 0
(2360 3810);
DISPLAY 0.680851 (2360 3810);
PAINT MONO (2360 3810);
FORCEPROP 0 LASTPIN (2350 3850) $PN 179
J 0
(2360 3860);
DISPLAY 0.680851 (2360 3860);
PAINT MONO (2360 3860);
FORCEPROP 0 LASTPIN (2350 2750) $PN 271
J 0
(2360 2760);
DISPLAY 0.680851 (2360 2760);
PAINT MONO (2360 2760);
FORCEPROP 0 LASTPIN (2350 2800) $PN 272
J 0
(2360 2810);
DISPLAY 0.680851 (2360 2810);
PAINT MONO (2360 2810);
FORCEPROP 0 LASTPIN (2350 3900) $PN 189
J 0
(2360 3910);
DISPLAY 0.680851 (2360 3910);
PAINT MONO (2360 3910);
FORCEPROP 0 LASTPIN (2350 3950) $PN 190
J 0
(2360 3960);
DISPLAY 0.680851 (2360 3960);
PAINT MONO (2360 3960);
FORCEPROP 0 LASTPIN (2350 2850) $PN 282
J 0
(2360 2860);
DISPLAY 0.680851 (2360 2860);
PAINT MONO (2360 2860);
FORCEPROP 0 LASTPIN (2350 2900) $PN 283
J 0
(2360 2910);
DISPLAY 0.680851 (2360 2910);
PAINT MONO (2360 2910);
FORCEPROP 0 LASTPIN (2350 4000) $PN 200
J 0
(2360 4010);
DISPLAY 0.680851 (2360 4010);
PAINT MONO (2360 4010);
FORCEPROP 0 LASTPIN (2350 4050) $PN 201
J 0
(2360 4060);
DISPLAY 0.680851 (2360 4060);
PAINT MONO (2360 4060);
FORCEPROP 0 LASTPIN (2350 2950) $PN 94
J 0
(2360 2960);
DISPLAY 0.680851 (2360 2960);
PAINT MONO (2360 2960);
FORCEPROP 0 LASTPIN (2350 3000) $PN 93
J 0
(2360 3010);
DISPLAY 0.680851 (2360 3010);
PAINT MONO (2360 3010);
FORCEPROP 1 LAST CDS_LMAN_SYM_OUTLINE -600,1150,600,-1150
J 0
(1600 3050);
DISPLAY 0.468085 (1600 3050);
PAINT GREEN (1600 3050);
DISPLAY INVISIBLE (1600 3050);
FORCEPROP 2 LAST CDS_LIB pure_quanta
J 0
(1600 3050);
DISPLAY INVISIBLE (1600 3050);
FORCEPROP 1 LAST NEEDS_NO_SIZE TRUE
J 0
(1600 3050);
DISPLAY 0.723404 (1600 3050);
PAINT GREEN (1600 3050);
DISPLAY INVISIBLE (1600 3050);
FORCEPROP 0 LAST $SEC 2
J 0
(1025 4575);
DISPLAY 0.680851 (1025 4575);
PAINT MONO (1025 4575);
DISPLAY INVISIBLE (1025 4575);
FORCEPROP 0 LAST CDS_SEC 2
J 0
(1025 4575);
DISPLAY 1.021277 (1025 4575);
DISPLAY INVISIBLE (1025 4575);
FORCEPROP 1 LAST PATH I178
J 0
(1600 3050);
DISPLAY 0.723404 (1600 3050);
PAINT GREEN (1600 3050);
DISPLAY INVISIBLE (1600 3050);
FORCEADD OFFPAGE..1
(-1700 1275);
FORCEPROP 2 LAST $XR7 89 
J 0
(-2582 1275);
DISPLAY 0.638298 (-2582 1275);
PAINT MONO (-2582 1275);
FORCEPROP 2 LAST $XR6 87 
J 0
(-2492 1275);
DISPLAY 0.638298 (-2492 1275);
PAINT MONO (-2492 1275);
FORCEPROP 2 LAST $XR5 86 
J 0
(-2402 1275);
DISPLAY 0.638298 (-2402 1275);
PAINT MONO (-2402 1275);
FORCEPROP 2 LAST $XR4 85 
J 0
(-2312 1275);
DISPLAY 0.638298 (-2312 1275);
PAINT MONO (-2312 1275);
FORCEPROP 2 LAST $XR3 84 
J 0
(-2222 1275);
DISPLAY 0.638298 (-2222 1275);
PAINT MONO (-2222 1275);
FORCEPROP 2 LAST $XR2 83 
J 0
(-2132 1275);
DISPLAY 0.638298 (-2132 1275);
PAINT MONO (-2132 1275);
FORCEPROP 2 LAST $XR1 82 
J 0
(-2042 1275);
DISPLAY 0.638298 (-2042 1275);
PAINT MONO (-2042 1275);
FORCEPROP 2 LAST $XR0 229 
J 0
(-1952 1275);
DISPLAY 0.638298 (-1952 1275);
PAINT MONO (-1952 1275);
FORCEPROP 2 LAST CDS_LIB standard
J 0
(-1700 1275);
PAINT MONO (-1700 1275);
DISPLAY INVISIBLE (-1700 1275);
FORCEPROP 1 LAST OFFPAGE TRUE
J 0
(-1375 1150);
DISPLAY 0.872340 (-1375 1150);
DISPLAY INVISIBLE (-1375 1150);
FORCEPROP 1 LAST COMMENT_BODY TRUE
J 0
(-1575 1175);
DISPLAY 0.872340 (-1575 1175);
PAINT GREEN (-1575 1175);
DISPLAY INVISIBLE (-1575 1175);
FORCEPROP 2 LAST PATH I179
J 2
(-2150 1325);
DISPLAY 1.021277 (-2150 1325);
DISPLAY INVISIBLE (-2150 1325);
FORCEADD OFFPAGE..1
(-2825 2800);
FORCEPROP 2 LAST $XR0 23 
J 0
(-3046 2800);
DISPLAY 0.638298 (-3046 2800);
PAINT MONO (-3046 2800);
FORCEPROP 2 LAST CDS_LIB standard
J 0
(-2825 2800);
PAINT MONO (-2825 2800);
DISPLAY INVISIBLE (-2825 2800);
FORCEPROP 1 LAST OFFPAGE TRUE
J 0
(-2500 2675);
DISPLAY 0.872340 (-2500 2675);
DISPLAY INVISIBLE (-2500 2675);
FORCEPROP 1 LAST COMMENT_BODY TRUE
J 0
(-2700 2700);
DISPLAY 0.872340 (-2700 2700);
PAINT GREEN (-2700 2700);
DISPLAY INVISIBLE (-2700 2700);
FORCEPROP 2 LAST PATH I18
J 0
(-2775 2875);
DISPLAY 1.021277 (-2775 2875);
DISPLAY INVISIBLE (-2775 2875);
FORCEADD Q_RES..1
(-2975 1325);
FORCEPROP 1 LAST PART_NUMBER CS04992FB07
J 0
(-2875 1300);
DISPLAY 0.404255 (-2875 1300);
DISPLAY INVISIBLE (-2875 1300);
FORCEPROP 1 LAST MATERIAL CHIP
J 0
(-2875 1275);
DISPLAY 0.404255 (-2875 1275);
FORCEPROP 1 LAST VALUE 49.9
J 2
(-2750 1325);
DISPLAY 0.510638 (-2750 1325);
FORCEPROP 1 LAST $LOCATION R3881
J 0
(-3150 1325);
DISPLAY 0.638298 (-3150 1325);
FORCEPROP 1 LASTPIN (-3075 1325) $PN 1
J 0
(-3063 1337);
DISPLAY 0.787234 (-3063 1337);
PAINT MONO (-3063 1337);
FORCEPROP 1 LASTPIN (-2875 1325) $PN 2
J 0
(-2913 1337);
DISPLAY 0.787234 (-2913 1337);
PAINT MONO (-2913 1337);
FORCEPROP 2 LAST CDS_LIB pure_quanta
J 0
(-2975 1325);
DISPLAY INVISIBLE (-2975 1325);
FORCEPROP 1 LAST PACK_TYPE 0402LF
J 0
(-2675 1325);
DISPLAY 0.510638 (-2675 1325);
DISPLAY INVISIBLE (-2675 1325);
FORCEPROP 1 LAST TOLERANCE 1%
J 0
(-2750 1325);
DISPLAY 0.510638 (-2750 1325);
DISPLAY INVISIBLE (-2750 1325);
FORCEPROP 1 LAST WATTAGE 1/16W
J 2
(-2675 1275);
DISPLAY 0.404255 (-2675 1275);
DISPLAY INVISIBLE (-2675 1275);
FORCEPROP 0 LAST CDS_LOCATION R3881
J 0
(-3100 1375);
DISPLAY 1.021277 (-3100 1375);
DISPLAY INVISIBLE (-3100 1375);
FORCEPROP 0 LAST $SEC 1
J 0
(-3100 1375);
DISPLAY 0.680851 (-3100 1375);
PAINT MONO (-3100 1375);
DISPLAY INVISIBLE (-3100 1375);
FORCEPROP 0 LAST CDS_SEC 1
J 0
(-3100 1375);
DISPLAY 1.021277 (-3100 1375);
DISPLAY INVISIBLE (-3100 1375);
FORCEPROP 1 LAST PATH I180
J 0
(-3025 1475);
DISPLAY 0.978723 (-3025 1475);
PAINT WHITE (-3025 1475);
DISPLAY INVISIBLE (-3025 1475);
FORCEADD OFFPAGE..1
(-2825 2750);
FORCEPROP 2 LAST $XR0 23 
J 0
(-3046 2750);
DISPLAY 0.638298 (-3046 2750);
PAINT MONO (-3046 2750);
FORCEPROP 2 LAST CDS_LIB standard
J 0
(-2825 2750);
PAINT MONO (-2825 2750);
DISPLAY INVISIBLE (-2825 2750);
FORCEPROP 1 LAST OFFPAGE TRUE
J 0
(-2500 2625);
DISPLAY 0.872340 (-2500 2625);
DISPLAY INVISIBLE (-2500 2625);
FORCEPROP 1 LAST COMMENT_BODY TRUE
J 0
(-2700 2650);
DISPLAY 0.872340 (-2700 2650);
PAINT GREEN (-2700 2650);
DISPLAY INVISIBLE (-2700 2650);
FORCEPROP 2 LAST PATH I19
J 0
(-2775 2825);
DISPLAY 1.021277 (-2775 2825);
DISPLAY INVISIBLE (-2775 2825);
FORCEADD Q_RES..2
(-1675 -100);
FORCEPROP 1 LAST PART_NUMBER CS41272FB07
J 0
(-1635 -225);
DISPLAY 0.978723 (-1635 -225);
DISPLAY INVISIBLE (-1635 -225);
FORCEPROP 1 LAST WATTAGE 1/16W
J 0
(-1635 -125);
DISPLAY 0.978723 (-1635 -125);
FORCEPROP 1 LAST PACK_TYPE 0402LF
J 0
(-1635 -275);
DISPLAY 0.978723 (-1635 -275);
FORCEPROP 1 LAST MATERIAL CHIP
J 0
(-1635 -175);
DISPLAY 0.978723 (-1635 -175);
FORCEPROP 1 LAST TOLERANCE 1%
J 0
(-1630 -75);
DISPLAY 0.978723 (-1630 -75);
FORCEPROP 1 LAST VALUE 127K
J 0
(-1630 -25);
DISPLAY 0.978723 (-1630 -25);
FORCEPROP 1 LAST $LOCATION R32
J 0
(-1630 25);
DISPLAY 0.978723 (-1630 25);
FORCEPROP 1 LASTPIN (-1675 0) $PN 1
J 0
(-1670 -38);
DISPLAY 0.787234 (-1670 -38);
FORCEPROP 1 LASTPIN (-1675 -200) $PN 2
J 0
(-1670 -190);
DISPLAY 0.787234 (-1670 -190);
FORCEPROP 2 LAST CDS_LIB pure_quanta
J 0
(-1675 -100);
PAINT MONO (-1675 -100);
DISPLAY INVISIBLE (-1675 -100);
FORCEPROP 2 LAST CDS_LOCATION R32
J 0
(-1625 125);
DISPLAY 1.021277 (-1625 125);
DISPLAY INVISIBLE (-1625 125);
FORCEPROP 2 LAST $SEC 1
J 0
(-1625 125);
DISPLAY 0.680851 (-1625 125);
PAINT MONO (-1625 125);
DISPLAY INVISIBLE (-1625 125);
FORCEPROP 2 LAST CDS_SEC 1
J 0
(-1625 125);
DISPLAY 1.021277 (-1625 125);
DISPLAY INVISIBLE (-1625 125);
FORCEPROP 1 LAST PATH I2
J 0
(-1625 75);
DISPLAY 0.978723 (-1625 75);
PAINT WHITE (-1625 75);
DISPLAY INVISIBLE (-1625 75);
FORCEADD OFFPAGE..1
(-2825 2950);
FORCEPROP 2 LAST $XR0 23 
J 0
(-3046 2950);
DISPLAY 0.638298 (-3046 2950);
PAINT MONO (-3046 2950);
FORCEPROP 2 LAST CDS_LIB standard
J 0
(-2825 2950);
PAINT MONO (-2825 2950);
DISPLAY INVISIBLE (-2825 2950);
FORCEPROP 1 LAST OFFPAGE TRUE
J 0
(-2500 2825);
DISPLAY 0.872340 (-2500 2825);
DISPLAY INVISIBLE (-2500 2825);
FORCEPROP 1 LAST COMMENT_BODY TRUE
J 0
(-2700 2850);
DISPLAY 0.872340 (-2700 2850);
PAINT GREEN (-2700 2850);
DISPLAY INVISIBLE (-2700 2850);
FORCEPROP 2 LAST PATH I20
J 0
(-2775 3025);
DISPLAY 1.021277 (-2775 3025);
DISPLAY INVISIBLE (-2775 3025);
FORCEADD OFFPAGE..1
(-2825 3250);
FORCEPROP 2 LAST $XR1 89 
J 0
(-3136 3250);
DISPLAY 0.638298 (-3136 3250);
PAINT MONO (-3136 3250);
FORCEPROP 2 LAST $XR0 23 
J 0
(-3046 3250);
DISPLAY 0.638298 (-3046 3250);
PAINT MONO (-3046 3250);
FORCEPROP 2 LAST CDS_LIB standard
J 0
(-2825 3250);
PAINT MONO (-2825 3250);
DISPLAY INVISIBLE (-2825 3250);
FORCEPROP 1 LAST OFFPAGE TRUE
J 0
(-2500 3125);
DISPLAY 0.872340 (-2500 3125);
DISPLAY INVISIBLE (-2500 3125);
FORCEPROP 1 LAST COMMENT_BODY TRUE
J 0
(-2700 3150);
DISPLAY 0.872340 (-2700 3150);
PAINT GREEN (-2700 3150);
DISPLAY INVISIBLE (-2700 3150);
FORCEPROP 2 LAST PATH I21
J 0
(-2775 3325);
DISPLAY 1.021277 (-2775 3325);
DISPLAY INVISIBLE (-2775 3325);
FORCEADD OFFPAGE..1
(-2825 3200);
FORCEPROP 2 LAST $XR1 89 
J 0
(-3136 3200);
DISPLAY 0.638298 (-3136 3200);
PAINT MONO (-3136 3200);
FORCEPROP 2 LAST $XR0 23 
J 0
(-3046 3200);
DISPLAY 0.638298 (-3046 3200);
PAINT MONO (-3046 3200);
FORCEPROP 2 LAST CDS_LIB standard
J 0
(-2825 3200);
PAINT MONO (-2825 3200);
DISPLAY INVISIBLE (-2825 3200);
FORCEPROP 1 LAST OFFPAGE TRUE
J 0
(-2500 3075);
DISPLAY 0.872340 (-2500 3075);
DISPLAY INVISIBLE (-2500 3075);
FORCEPROP 1 LAST COMMENT_BODY TRUE
J 0
(-2700 3100);
DISPLAY 0.872340 (-2700 3100);
PAINT GREEN (-2700 3100);
DISPLAY INVISIBLE (-2700 3100);
FORCEPROP 2 LAST PATH I22
J 0
(-2775 3275);
DISPLAY 1.021277 (-2775 3275);
DISPLAY INVISIBLE (-2775 3275);
FORCEADD OFFPAGE..1
(-2825 3100);
FORCEPROP 2 LAST $XR0 23 
J 0
(-3046 3100);
DISPLAY 0.638298 (-3046 3100);
PAINT MONO (-3046 3100);
FORCEPROP 2 LAST CDS_LIB standard
J 0
(-2825 3100);
PAINT MONO (-2825 3100);
DISPLAY INVISIBLE (-2825 3100);
FORCEPROP 1 LAST OFFPAGE TRUE
J 0
(-2500 2975);
DISPLAY 0.872340 (-2500 2975);
DISPLAY INVISIBLE (-2500 2975);
FORCEPROP 1 LAST COMMENT_BODY TRUE
J 0
(-2700 3000);
DISPLAY 0.872340 (-2700 3000);
PAINT GREEN (-2700 3000);
DISPLAY INVISIBLE (-2700 3000);
FORCEPROP 2 LAST PATH I23
J 0
(-2775 3175);
DISPLAY 1.021277 (-2775 3175);
DISPLAY INVISIBLE (-2775 3175);
FORCEADD OFFPAGE..1
(-2825 3050);
FORCEPROP 2 LAST $XR0 23 
J 0
(-3046 3050);
DISPLAY 0.638298 (-3046 3050);
PAINT MONO (-3046 3050);
FORCEPROP 2 LAST CDS_LIB standard
J 0
(-2825 3050);
PAINT MONO (-2825 3050);
DISPLAY INVISIBLE (-2825 3050);
FORCEPROP 1 LAST OFFPAGE TRUE
J 0
(-2500 2925);
DISPLAY 0.872340 (-2500 2925);
DISPLAY INVISIBLE (-2500 2925);
FORCEPROP 1 LAST COMMENT_BODY TRUE
J 0
(-2700 2950);
DISPLAY 0.872340 (-2700 2950);
PAINT GREEN (-2700 2950);
DISPLAY INVISIBLE (-2700 2950);
FORCEPROP 2 LAST PATH I24
J 0
(-2775 3125);
DISPLAY 1.021277 (-2775 3125);
DISPLAY INVISIBLE (-2775 3125);
FORCEADD OFFPAGE..1
(-2825 3675);
FORCEPROP 2 LAST $XR1 89 
J 0
(-3136 3675);
DISPLAY 0.638298 (-3136 3675);
PAINT MONO (-3136 3675);
FORCEPROP 2 LAST $XR0 23 
J 0
(-3046 3675);
DISPLAY 0.638298 (-3046 3675);
PAINT MONO (-3046 3675);
FORCEPROP 2 LAST CDS_LIB standard
J 0
(-2825 3675);
PAINT MONO (-2825 3675);
DISPLAY INVISIBLE (-2825 3675);
FORCEPROP 1 LAST OFFPAGE TRUE
J 0
(-2500 3550);
DISPLAY 0.872340 (-2500 3550);
DISPLAY INVISIBLE (-2500 3550);
FORCEPROP 1 LAST COMMENT_BODY TRUE
J 0
(-2700 3575);
DISPLAY 0.872340 (-2700 3575);
PAINT GREEN (-2700 3575);
DISPLAY INVISIBLE (-2700 3575);
FORCEPROP 2 LAST PATH I25
J 0
(-2775 3750);
DISPLAY 1.021277 (-2775 3750);
DISPLAY INVISIBLE (-2775 3750);
FORCEADD TAP..1
R 2
(-1900 2000);
FORCEPROP 3 LASTPIN (-1850 2000) SIG_NAME M_D_CPU0_SB_CB<3>
J 0
(-1840 2010);
DISPLAY 0.659574 (-1840 2010);
PAINT MONO (-1840 2010);
DISPLAY INVISIBLE (-1840 2010);
FORCEPROP 1 LASTPIN (-1850 2000) BN 3
J 2
(-1838 2008);
DISPLAY 0.680851 (-1838 2008);
PAINT GREEN (-1838 2008);
FORCEPROP 2 LAST CDS_LIB standard
J 0
(-1900 2000);
DISPLAY INVISIBLE (-1900 2000);
FORCEPROP 1 LAST BODY_TYPE PLUMBING
J 2
(-1900 2050);
DISPLAY 0.872340 (-1900 2050);
PAINT GREEN (-1900 2050);
DISPLAY INVISIBLE (-1900 2050);
FORCEPROP 1 LAST HDL_TAP TRUE
J 2
(-2225 1875);
DISPLAY 0.872340 (-2225 1875);
DISPLAY INVISIBLE (-2225 1875);
FORCEPROP 1 LAST PATH I26
J 2
(-1898 2000);
DISPLAY 0.872340 (-1898 2000);
PAINT GREEN (-1898 2000);
DISPLAY INVISIBLE (-1898 2000);
FORCEADD TAP..1
R 2
(-1900 1950);
FORCEPROP 3 LASTPIN (-1850 1950) SIG_NAME M_D_CPU0_SB_CB<2>
J 0
(-1840 1960);
DISPLAY 0.659574 (-1840 1960);
PAINT MONO (-1840 1960);
DISPLAY INVISIBLE (-1840 1960);
FORCEPROP 1 LASTPIN (-1850 1950) BN 2
J 2
(-1838 1958);
DISPLAY 0.680851 (-1838 1958);
PAINT GREEN (-1838 1958);
FORCEPROP 2 LAST CDS_LIB standard
J 0
(-1900 1950);
DISPLAY INVISIBLE (-1900 1950);
FORCEPROP 1 LAST BODY_TYPE PLUMBING
J 2
(-1900 2000);
DISPLAY 0.872340 (-1900 2000);
PAINT GREEN (-1900 2000);
DISPLAY INVISIBLE (-1900 2000);
FORCEPROP 1 LAST HDL_TAP TRUE
J 2
(-2225 1825);
DISPLAY 0.872340 (-2225 1825);
DISPLAY INVISIBLE (-2225 1825);
FORCEPROP 1 LAST PATH I27
J 2
(-1898 1950);
DISPLAY 0.872340 (-1898 1950);
PAINT GREEN (-1898 1950);
DISPLAY INVISIBLE (-1898 1950);
FORCEADD TAP..1
R 2
(-1900 2050);
FORCEPROP 3 LASTPIN (-1850 2050) SIG_NAME M_D_CPU0_SB_CB<4>
J 0
(-1840 2060);
DISPLAY 0.659574 (-1840 2060);
PAINT MONO (-1840 2060);
DISPLAY INVISIBLE (-1840 2060);
FORCEPROP 1 LASTPIN (-1850 2050) BN 4
J 2
(-1838 2058);
DISPLAY 0.680851 (-1838 2058);
PAINT GREEN (-1838 2058);
FORCEPROP 2 LAST CDS_LIB standard
J 0
(-1900 2050);
DISPLAY INVISIBLE (-1900 2050);
FORCEPROP 1 LAST BODY_TYPE PLUMBING
J 2
(-1900 2100);
DISPLAY 0.872340 (-1900 2100);
PAINT GREEN (-1900 2100);
DISPLAY INVISIBLE (-1900 2100);
FORCEPROP 1 LAST HDL_TAP TRUE
J 2
(-2225 1925);
DISPLAY 0.872340 (-2225 1925);
DISPLAY INVISIBLE (-2225 1925);
FORCEPROP 1 LAST PATH I28
J 2
(-1898 2050);
DISPLAY 0.872340 (-1898 2050);
PAINT GREEN (-1898 2050);
DISPLAY INVISIBLE (-1898 2050);
FORCEADD TAP..1
R 2
(-1900 2100);
FORCEPROP 3 LASTPIN (-1850 2100) SIG_NAME M_D_CPU0_SB_CB<5>
J 0
(-1840 2110);
DISPLAY 0.659574 (-1840 2110);
PAINT MONO (-1840 2110);
DISPLAY INVISIBLE (-1840 2110);
FORCEPROP 1 LASTPIN (-1850 2100) BN 5
J 2
(-1838 2108);
DISPLAY 0.680851 (-1838 2108);
PAINT GREEN (-1838 2108);
FORCEPROP 2 LAST CDS_LIB standard
J 0
(-1900 2100);
DISPLAY INVISIBLE (-1900 2100);
FORCEPROP 1 LAST BODY_TYPE PLUMBING
J 2
(-1900 2150);
DISPLAY 0.872340 (-1900 2150);
PAINT GREEN (-1900 2150);
DISPLAY INVISIBLE (-1900 2150);
FORCEPROP 1 LAST HDL_TAP TRUE
J 2
(-2225 1975);
DISPLAY 0.872340 (-2225 1975);
DISPLAY INVISIBLE (-2225 1975);
FORCEPROP 1 LAST PATH I29
J 2
(-1898 2100);
DISPLAY 0.872340 (-1898 2100);
PAINT GREEN (-1898 2100);
DISPLAY INVISIBLE (-1898 2100);
FORCEADD OFFPAGE..2
R 2
(-2825 100);
FORCEPROP 2 LAST $XR0 88 
J 0
(-3049 100);
DISPLAY 0.638298 (-3049 100);
PAINT MONO (-3049 100);
FORCEPROP 2 LAST CDS_LIB standard
J 0
(-2825 100);
PAINT MONO (-2825 100);
DISPLAY INVISIBLE (-2825 100);
FORCEPROP 1 LAST OFFPAGE TRUE
J 2
(-3150 -25);
DISPLAY 0.872340 (-3150 -25);
DISPLAY INVISIBLE (-3150 -25);
FORCEPROP 1 LAST COMMENT_BODY TRUE
J 2
(-2780 5);
DISPLAY 0.872340 (-2780 5);
PAINT GREEN (-2780 5);
DISPLAY INVISIBLE (-2780 5);
FORCEPROP 2 LAST PATH I3
J 0
(-2775 175);
DISPLAY 1.021277 (-2775 175);
DISPLAY INVISIBLE (-2775 175);
FORCEADD TAP..1
R 2
(-1900 2150);
FORCEPROP 3 LASTPIN (-1850 2150) SIG_NAME M_D_CPU0_SB_CB<6>
J 0
(-1840 2160);
DISPLAY 0.659574 (-1840 2160);
PAINT MONO (-1840 2160);
DISPLAY INVISIBLE (-1840 2160);
FORCEPROP 1 LASTPIN (-1850 2150) BN 6
J 2
(-1838 2158);
DISPLAY 0.680851 (-1838 2158);
PAINT GREEN (-1838 2158);
FORCEPROP 2 LAST CDS_LIB standard
J 0
(-1900 2150);
DISPLAY INVISIBLE (-1900 2150);
FORCEPROP 1 LAST BODY_TYPE PLUMBING
J 2
(-1900 2200);
DISPLAY 0.872340 (-1900 2200);
PAINT GREEN (-1900 2200);
DISPLAY INVISIBLE (-1900 2200);
FORCEPROP 1 LAST HDL_TAP TRUE
J 2
(-2225 2025);
DISPLAY 0.872340 (-2225 2025);
DISPLAY INVISIBLE (-2225 2025);
FORCEPROP 1 LAST PATH I30
J 2
(-1898 2150);
DISPLAY 0.872340 (-1898 2150);
PAINT GREEN (-1898 2150);
DISPLAY INVISIBLE (-1898 2150);
FORCEADD TAP..1
R 2
(-1900 2200);
FORCEPROP 3 LASTPIN (-1850 2200) SIG_NAME M_D_CPU0_SB_CB<7>
J 0
(-1840 2210);
DISPLAY 0.659574 (-1840 2210);
PAINT MONO (-1840 2210);
DISPLAY INVISIBLE (-1840 2210);
FORCEPROP 1 LASTPIN (-1850 2200) BN 7
J 2
(-1838 2208);
DISPLAY 0.680851 (-1838 2208);
PAINT GREEN (-1838 2208);
FORCEPROP 2 LAST CDS_LIB standard
J 0
(-1900 2200);
DISPLAY INVISIBLE (-1900 2200);
FORCEPROP 1 LAST BODY_TYPE PLUMBING
J 2
(-1900 2250);
DISPLAY 0.872340 (-1900 2250);
PAINT GREEN (-1900 2250);
DISPLAY INVISIBLE (-1900 2250);
FORCEPROP 1 LAST HDL_TAP TRUE
J 2
(-2225 2075);
DISPLAY 0.872340 (-2225 2075);
DISPLAY INVISIBLE (-2225 2075);
FORCEPROP 1 LAST PATH I31
J 2
(-1898 2200);
DISPLAY 0.872340 (-1898 2200);
PAINT GREEN (-1898 2200);
DISPLAY INVISIBLE (-1898 2200);
FORCEADD TAP..1
R 2
(-1900 2300);
FORCEPROP 3 LASTPIN (-1850 2300) SIG_NAME M_D_CPU0_SA_CB<0>
J 0
(-1840 2310);
DISPLAY 0.659574 (-1840 2310);
PAINT MONO (-1840 2310);
DISPLAY INVISIBLE (-1840 2310);
FORCEPROP 1 LASTPIN (-1850 2300) BN 0
J 2
(-1838 2308);
DISPLAY 0.680851 (-1838 2308);
PAINT GREEN (-1838 2308);
FORCEPROP 2 LAST CDS_LIB standard
J 0
(-1900 2300);
PAINT MONO (-1900 2300);
DISPLAY INVISIBLE (-1900 2300);
FORCEPROP 1 LAST BODY_TYPE PLUMBING
J 2
(-1900 2350);
DISPLAY 0.872340 (-1900 2350);
PAINT GREEN (-1900 2350);
DISPLAY INVISIBLE (-1900 2350);
FORCEPROP 1 LAST HDL_TAP TRUE
J 2
(-2225 2175);
DISPLAY 0.872340 (-2225 2175);
DISPLAY INVISIBLE (-2225 2175);
FORCEPROP 1 LAST PATH I32
J 2
(-1898 2300);
DISPLAY 0.872340 (-1898 2300);
PAINT GREEN (-1898 2300);
DISPLAY INVISIBLE (-1898 2300);
FORCEADD TAP..1
R 2
(-1900 2400);
FORCEPROP 3 LASTPIN (-1850 2400) SIG_NAME M_D_CPU0_SA_CB<2>
J 0
(-1840 2410);
DISPLAY 0.659574 (-1840 2410);
PAINT MONO (-1840 2410);
DISPLAY INVISIBLE (-1840 2410);
FORCEPROP 1 LASTPIN (-1850 2400) BN 2
J 2
(-1838 2408);
DISPLAY 0.680851 (-1838 2408);
PAINT GREEN (-1838 2408);
FORCEPROP 2 LAST CDS_LIB standard
J 0
(-1900 2400);
DISPLAY INVISIBLE (-1900 2400);
FORCEPROP 1 LAST BODY_TYPE PLUMBING
J 2
(-1900 2450);
DISPLAY 0.872340 (-1900 2450);
PAINT GREEN (-1900 2450);
DISPLAY INVISIBLE (-1900 2450);
FORCEPROP 1 LAST HDL_TAP TRUE
J 2
(-2225 2275);
DISPLAY 0.872340 (-2225 2275);
DISPLAY INVISIBLE (-2225 2275);
FORCEPROP 1 LAST PATH I33
J 2
(-1898 2400);
DISPLAY 0.872340 (-1898 2400);
PAINT GREEN (-1898 2400);
DISPLAY INVISIBLE (-1898 2400);
FORCEADD TAP..1
R 2
(-1900 2350);
FORCEPROP 3 LASTPIN (-1850 2350) SIG_NAME M_D_CPU0_SA_CB<1>
J 0
(-1840 2360);
DISPLAY 0.659574 (-1840 2360);
PAINT MONO (-1840 2360);
DISPLAY INVISIBLE (-1840 2360);
FORCEPROP 1 LASTPIN (-1850 2350) BN 1
J 2
(-1838 2358);
DISPLAY 0.680851 (-1838 2358);
PAINT GREEN (-1838 2358);
FORCEPROP 2 LAST CDS_LIB standard
J 0
(-1900 2350);
DISPLAY INVISIBLE (-1900 2350);
FORCEPROP 1 LAST BODY_TYPE PLUMBING
J 2
(-1900 2400);
DISPLAY 0.872340 (-1900 2400);
PAINT GREEN (-1900 2400);
DISPLAY INVISIBLE (-1900 2400);
FORCEPROP 1 LAST HDL_TAP TRUE
J 2
(-2225 2225);
DISPLAY 0.872340 (-2225 2225);
DISPLAY INVISIBLE (-2225 2225);
FORCEPROP 1 LAST PATH I34
J 2
(-1898 2350);
DISPLAY 0.872340 (-1898 2350);
PAINT GREEN (-1898 2350);
DISPLAY INVISIBLE (-1898 2350);
FORCEADD TAP..1
R 2
(-1900 2450);
FORCEPROP 3 LASTPIN (-1850 2450) SIG_NAME M_D_CPU0_SA_CB<3>
J 0
(-1840 2460);
DISPLAY 0.659574 (-1840 2460);
PAINT MONO (-1840 2460);
DISPLAY INVISIBLE (-1840 2460);
FORCEPROP 1 LASTPIN (-1850 2450) BN 3
J 2
(-1838 2458);
DISPLAY 0.680851 (-1838 2458);
PAINT GREEN (-1838 2458);
FORCEPROP 2 LAST CDS_LIB standard
J 0
(-1900 2450);
DISPLAY INVISIBLE (-1900 2450);
FORCEPROP 1 LAST BODY_TYPE PLUMBING
J 2
(-1900 2500);
DISPLAY 0.872340 (-1900 2500);
PAINT GREEN (-1900 2500);
DISPLAY INVISIBLE (-1900 2500);
FORCEPROP 1 LAST HDL_TAP TRUE
J 2
(-2225 2325);
DISPLAY 0.872340 (-2225 2325);
DISPLAY INVISIBLE (-2225 2325);
FORCEPROP 1 LAST PATH I35
J 2
(-1898 2450);
DISPLAY 0.872340 (-1898 2450);
PAINT GREEN (-1898 2450);
DISPLAY INVISIBLE (-1898 2450);
FORCEADD TAP..1
R 2
(-1900 2550);
FORCEPROP 3 LASTPIN (-1850 2550) SIG_NAME M_D_CPU0_SA_CB<5>
J 0
(-1840 2560);
DISPLAY 0.659574 (-1840 2560);
PAINT MONO (-1840 2560);
DISPLAY INVISIBLE (-1840 2560);
FORCEPROP 1 LASTPIN (-1850 2550) BN 5
J 2
(-1838 2558);
DISPLAY 0.680851 (-1838 2558);
PAINT GREEN (-1838 2558);
FORCEPROP 2 LAST CDS_LIB standard
J 0
(-1900 2550);
DISPLAY INVISIBLE (-1900 2550);
FORCEPROP 1 LAST BODY_TYPE PLUMBING
J 2
(-1900 2600);
DISPLAY 0.872340 (-1900 2600);
PAINT GREEN (-1900 2600);
DISPLAY INVISIBLE (-1900 2600);
FORCEPROP 1 LAST HDL_TAP TRUE
J 2
(-2225 2425);
DISPLAY 0.872340 (-2225 2425);
DISPLAY INVISIBLE (-2225 2425);
FORCEPROP 1 LAST PATH I36
J 2
(-1898 2550);
DISPLAY 0.872340 (-1898 2550);
PAINT GREEN (-1898 2550);
DISPLAY INVISIBLE (-1898 2550);
FORCEADD TAP..1
R 2
(-1900 2500);
FORCEPROP 3 LASTPIN (-1850 2500) SIG_NAME M_D_CPU0_SA_CB<4>
J 0
(-1840 2510);
DISPLAY 0.659574 (-1840 2510);
PAINT MONO (-1840 2510);
DISPLAY INVISIBLE (-1840 2510);
FORCEPROP 1 LASTPIN (-1850 2500) BN 4
J 2
(-1838 2508);
DISPLAY 0.680851 (-1838 2508);
PAINT GREEN (-1838 2508);
FORCEPROP 2 LAST CDS_LIB standard
J 0
(-1900 2500);
DISPLAY INVISIBLE (-1900 2500);
FORCEPROP 1 LAST BODY_TYPE PLUMBING
J 2
(-1900 2550);
DISPLAY 0.872340 (-1900 2550);
PAINT GREEN (-1900 2550);
DISPLAY INVISIBLE (-1900 2550);
FORCEPROP 1 LAST HDL_TAP TRUE
J 2
(-2225 2375);
DISPLAY 0.872340 (-2225 2375);
DISPLAY INVISIBLE (-2225 2375);
FORCEPROP 1 LAST PATH I37
J 2
(-1898 2500);
DISPLAY 0.872340 (-1898 2500);
PAINT GREEN (-1898 2500);
DISPLAY INVISIBLE (-1898 2500);
FORCEADD TAP..1
R 2
(-1900 2600);
FORCEPROP 3 LASTPIN (-1850 2600) SIG_NAME M_D_CPU0_SA_CB<6>
J 0
(-1840 2610);
DISPLAY 0.659574 (-1840 2610);
PAINT MONO (-1840 2610);
DISPLAY INVISIBLE (-1840 2610);
FORCEPROP 1 LASTPIN (-1850 2600) BN 6
J 2
(-1838 2608);
DISPLAY 0.680851 (-1838 2608);
PAINT GREEN (-1838 2608);
FORCEPROP 2 LAST CDS_LIB standard
J 0
(-1900 2600);
DISPLAY INVISIBLE (-1900 2600);
FORCEPROP 1 LAST BODY_TYPE PLUMBING
J 2
(-1900 2650);
DISPLAY 0.872340 (-1900 2650);
PAINT GREEN (-1900 2650);
DISPLAY INVISIBLE (-1900 2650);
FORCEPROP 1 LAST HDL_TAP TRUE
J 2
(-2225 2475);
DISPLAY 0.872340 (-2225 2475);
DISPLAY INVISIBLE (-2225 2475);
FORCEPROP 1 LAST PATH I38
J 2
(-1898 2600);
DISPLAY 0.872340 (-1898 2600);
PAINT GREEN (-1898 2600);
DISPLAY INVISIBLE (-1898 2600);
FORCEADD TAP..1
R 2
(-1900 2650);
FORCEPROP 3 LASTPIN (-1850 2650) SIG_NAME M_D_CPU0_SA_CB<7>
J 0
(-1840 2660);
DISPLAY 0.659574 (-1840 2660);
PAINT MONO (-1840 2660);
DISPLAY INVISIBLE (-1840 2660);
FORCEPROP 1 LASTPIN (-1850 2650) BN 7
J 2
(-1838 2658);
DISPLAY 0.680851 (-1838 2658);
PAINT GREEN (-1838 2658);
FORCEPROP 2 LAST CDS_LIB standard
J 0
(-1900 2650);
DISPLAY INVISIBLE (-1900 2650);
FORCEPROP 1 LAST BODY_TYPE PLUMBING
J 2
(-1900 2700);
DISPLAY 0.872340 (-1900 2700);
PAINT GREEN (-1900 2700);
DISPLAY INVISIBLE (-1900 2700);
FORCEPROP 1 LAST HDL_TAP TRUE
J 2
(-2225 2525);
DISPLAY 0.872340 (-2225 2525);
DISPLAY INVISIBLE (-2225 2525);
FORCEPROP 1 LAST PATH I39
J 2
(-1898 2650);
DISPLAY 0.872340 (-1898 2650);
PAINT GREEN (-1898 2650);
DISPLAY INVISIBLE (-1898 2650);
FORCEADD OFFPAGE..2
R 2
(-2825 650);
FORCEPROP 2 LAST $XR0 23 
J 0
(-3049 650);
DISPLAY 0.638298 (-3049 650);
PAINT MONO (-3049 650);
FORCEPROP 2 LAST CDS_LIB standard
J 0
(-2825 650);
PAINT MONO (-2825 650);
DISPLAY INVISIBLE (-2825 650);
FORCEPROP 1 LAST OFFPAGE TRUE
J 2
(-3150 525);
DISPLAY 0.872340 (-3150 525);
DISPLAY INVISIBLE (-3150 525);
FORCEPROP 1 LAST COMMENT_BODY TRUE
J 2
(-2780 555);
DISPLAY 0.872340 (-2780 555);
PAINT GREEN (-2780 555);
DISPLAY INVISIBLE (-2780 555);
FORCEPROP 2 LAST PATH I4
J 0
(-2775 725);
DISPLAY 1.021277 (-2775 725);
DISPLAY INVISIBLE (-2775 725);
FORCEADD TAP..1
R 2
(-1900 3350);
FORCEPROP 3 LASTPIN (-1850 3350) SIG_NAME M_D_CPU0_SB_CA<0>
J 0
(-1840 3360);
DISPLAY 0.659574 (-1840 3360);
PAINT MONO (-1840 3360);
DISPLAY INVISIBLE (-1840 3360);
FORCEPROP 1 LASTPIN (-1850 3350) BN 0
J 2
(-1838 3358);
DISPLAY 0.680851 (-1838 3358);
PAINT GREEN (-1838 3358);
FORCEPROP 2 LAST CDS_LIB standard
J 0
(-1900 3350);
DISPLAY INVISIBLE (-1900 3350);
FORCEPROP 1 LAST BODY_TYPE PLUMBING
J 2
(-1900 3400);
DISPLAY 0.872340 (-1900 3400);
PAINT GREEN (-1900 3400);
DISPLAY INVISIBLE (-1900 3400);
FORCEPROP 1 LAST HDL_TAP TRUE
J 2
(-2225 3225);
DISPLAY 0.872340 (-2225 3225);
DISPLAY INVISIBLE (-2225 3225);
FORCEPROP 1 LAST PATH I40
J 2
(-1898 3350);
DISPLAY 0.872340 (-1898 3350);
PAINT GREEN (-1898 3350);
DISPLAY INVISIBLE (-1898 3350);
FORCEADD TAP..1
R 2
(-1900 3450);
FORCEPROP 3 LASTPIN (-1850 3450) SIG_NAME M_D_CPU0_SB_CA<2>
J 0
(-1840 3460);
DISPLAY 0.659574 (-1840 3460);
PAINT MONO (-1840 3460);
DISPLAY INVISIBLE (-1840 3460);
FORCEPROP 1 LASTPIN (-1850 3450) BN 2
J 2
(-1838 3458);
DISPLAY 0.680851 (-1838 3458);
PAINT GREEN (-1838 3458);
FORCEPROP 2 LAST CDS_LIB standard
J 0
(-1900 3450);
DISPLAY INVISIBLE (-1900 3450);
FORCEPROP 1 LAST BODY_TYPE PLUMBING
J 2
(-1900 3500);
DISPLAY 0.872340 (-1900 3500);
PAINT GREEN (-1900 3500);
DISPLAY INVISIBLE (-1900 3500);
FORCEPROP 1 LAST HDL_TAP TRUE
J 2
(-2225 3325);
DISPLAY 0.872340 (-2225 3325);
DISPLAY INVISIBLE (-2225 3325);
FORCEPROP 1 LAST PATH I41
J 2
(-1898 3450);
DISPLAY 0.872340 (-1898 3450);
PAINT GREEN (-1898 3450);
DISPLAY INVISIBLE (-1898 3450);
FORCEADD TAP..1
R 2
(-1900 3400);
FORCEPROP 3 LASTPIN (-1850 3400) SIG_NAME M_D_CPU0_SB_CA<1>
J 0
(-1840 3410);
DISPLAY 0.659574 (-1840 3410);
PAINT MONO (-1840 3410);
DISPLAY INVISIBLE (-1840 3410);
FORCEPROP 1 LASTPIN (-1850 3400) BN 1
J 2
(-1838 3408);
DISPLAY 0.680851 (-1838 3408);
PAINT GREEN (-1838 3408);
FORCEPROP 2 LAST CDS_LIB standard
J 0
(-1900 3400);
DISPLAY INVISIBLE (-1900 3400);
FORCEPROP 1 LAST BODY_TYPE PLUMBING
J 2
(-1900 3450);
DISPLAY 0.872340 (-1900 3450);
PAINT GREEN (-1900 3450);
DISPLAY INVISIBLE (-1900 3450);
FORCEPROP 1 LAST HDL_TAP TRUE
J 2
(-2225 3275);
DISPLAY 0.872340 (-2225 3275);
DISPLAY INVISIBLE (-2225 3275);
FORCEPROP 1 LAST PATH I42
J 2
(-1898 3400);
DISPLAY 0.872340 (-1898 3400);
PAINT GREEN (-1898 3400);
DISPLAY INVISIBLE (-1898 3400);
FORCEADD TAP..1
R 2
(-1900 3500);
FORCEPROP 3 LASTPIN (-1850 3500) SIG_NAME M_D_CPU0_SB_CA<3>
J 0
(-1840 3510);
DISPLAY 0.659574 (-1840 3510);
PAINT MONO (-1840 3510);
DISPLAY INVISIBLE (-1840 3510);
FORCEPROP 1 LASTPIN (-1850 3500) BN 3
J 2
(-1838 3508);
DISPLAY 0.680851 (-1838 3508);
PAINT GREEN (-1838 3508);
FORCEPROP 2 LAST CDS_LIB standard
J 0
(-1900 3500);
DISPLAY INVISIBLE (-1900 3500);
FORCEPROP 1 LAST BODY_TYPE PLUMBING
J 2
(-1900 3550);
DISPLAY 0.872340 (-1900 3550);
PAINT GREEN (-1900 3550);
DISPLAY INVISIBLE (-1900 3550);
FORCEPROP 1 LAST HDL_TAP TRUE
J 2
(-2225 3375);
DISPLAY 0.872340 (-2225 3375);
DISPLAY INVISIBLE (-2225 3375);
FORCEPROP 1 LAST PATH I43
J 2
(-1898 3500);
DISPLAY 0.872340 (-1898 3500);
PAINT GREEN (-1898 3500);
DISPLAY INVISIBLE (-1898 3500);
FORCEADD TAP..1
R 2
(-1900 3550);
FORCEPROP 3 LASTPIN (-1850 3550) SIG_NAME M_D_CPU0_SB_CA<4>
J 0
(-1840 3560);
DISPLAY 0.659574 (-1840 3560);
PAINT MONO (-1840 3560);
DISPLAY INVISIBLE (-1840 3560);
FORCEPROP 1 LASTPIN (-1850 3550) BN 4
J 2
(-1838 3558);
DISPLAY 0.680851 (-1838 3558);
PAINT GREEN (-1838 3558);
FORCEPROP 2 LAST CDS_LIB standard
J 0
(-1900 3550);
DISPLAY INVISIBLE (-1900 3550);
FORCEPROP 1 LAST BODY_TYPE PLUMBING
J 2
(-1900 3600);
DISPLAY 0.872340 (-1900 3600);
PAINT GREEN (-1900 3600);
DISPLAY INVISIBLE (-1900 3600);
FORCEPROP 1 LAST HDL_TAP TRUE
J 2
(-2225 3425);
DISPLAY 0.872340 (-2225 3425);
DISPLAY INVISIBLE (-2225 3425);
FORCEPROP 1 LAST PATH I44
J 2
(-1898 3550);
DISPLAY 0.872340 (-1898 3550);
PAINT GREEN (-1898 3550);
DISPLAY INVISIBLE (-1898 3550);
FORCEADD TAP..1
R 2
(-1900 3600);
FORCEPROP 3 LASTPIN (-1850 3600) SIG_NAME M_D_CPU0_SB_CA<5>
J 0
(-1840 3610);
DISPLAY 0.659574 (-1840 3610);
PAINT MONO (-1840 3610);
DISPLAY INVISIBLE (-1840 3610);
FORCEPROP 1 LASTPIN (-1850 3600) BN 5
J 2
(-1838 3608);
DISPLAY 0.680851 (-1838 3608);
PAINT GREEN (-1838 3608);
FORCEPROP 2 LAST CDS_LIB standard
J 0
(-1900 3600);
DISPLAY INVISIBLE (-1900 3600);
FORCEPROP 1 LAST BODY_TYPE PLUMBING
J 2
(-1900 3650);
DISPLAY 0.872340 (-1900 3650);
PAINT GREEN (-1900 3650);
DISPLAY INVISIBLE (-1900 3650);
FORCEPROP 1 LAST HDL_TAP TRUE
J 2
(-2225 3475);
DISPLAY 0.872340 (-2225 3475);
DISPLAY INVISIBLE (-2225 3475);
FORCEPROP 1 LAST PATH I45
J 2
(-1898 3600);
DISPLAY 0.872340 (-1898 3600);
PAINT GREEN (-1898 3600);
DISPLAY INVISIBLE (-1898 3600);
FORCEADD TAP..1
R 2
(-1900 3650);
FORCEPROP 3 LASTPIN (-1850 3650) SIG_NAME M_D_CPU0_SB_CA<6>
J 0
(-1840 3660);
DISPLAY 0.659574 (-1840 3660);
PAINT MONO (-1840 3660);
DISPLAY INVISIBLE (-1840 3660);
FORCEPROP 1 LASTPIN (-1850 3650) BN 6
J 2
(-1838 3658);
DISPLAY 0.680851 (-1838 3658);
PAINT GREEN (-1838 3658);
FORCEPROP 2 LAST CDS_LIB standard
J 0
(-1900 3650);
DISPLAY INVISIBLE (-1900 3650);
FORCEPROP 1 LAST BODY_TYPE PLUMBING
J 2
(-1900 3700);
DISPLAY 0.872340 (-1900 3700);
PAINT GREEN (-1900 3700);
DISPLAY INVISIBLE (-1900 3700);
FORCEPROP 1 LAST HDL_TAP TRUE
J 2
(-2225 3525);
DISPLAY 0.872340 (-2225 3525);
DISPLAY INVISIBLE (-2225 3525);
FORCEPROP 1 LAST PATH I46
J 2
(-1898 3650);
DISPLAY 0.872340 (-1898 3650);
PAINT GREEN (-1898 3650);
DISPLAY INVISIBLE (-1898 3650);
FORCEADD TAP..1
R 2
(-1900 3800);
FORCEPROP 3 LASTPIN (-1850 3800) SIG_NAME M_D_CPU0_SA_CA<1>
J 0
(-1840 3810);
DISPLAY 0.659574 (-1840 3810);
PAINT MONO (-1840 3810);
DISPLAY INVISIBLE (-1840 3810);
FORCEPROP 1 LASTPIN (-1850 3800) BN 1
J 2
(-1838 3808);
DISPLAY 0.680851 (-1838 3808);
PAINT GREEN (-1838 3808);
FORCEPROP 2 LAST CDS_LIB standard
J 0
(-1900 3800);
DISPLAY INVISIBLE (-1900 3800);
FORCEPROP 1 LAST BODY_TYPE PLUMBING
J 2
(-1900 3850);
DISPLAY 0.872340 (-1900 3850);
PAINT GREEN (-1900 3850);
DISPLAY INVISIBLE (-1900 3850);
FORCEPROP 1 LAST HDL_TAP TRUE
J 2
(-2225 3675);
DISPLAY 0.872340 (-2225 3675);
DISPLAY INVISIBLE (-2225 3675);
FORCEPROP 1 LAST PATH I47
J 2
(-1898 3800);
DISPLAY 0.872340 (-1898 3800);
PAINT GREEN (-1898 3800);
DISPLAY INVISIBLE (-1898 3800);
FORCEADD TAP..1
R 2
(-1900 3750);
FORCEPROP 3 LASTPIN (-1850 3750) SIG_NAME M_D_CPU0_SA_CA<0>
J 0
(-1840 3760);
DISPLAY 0.659574 (-1840 3760);
PAINT MONO (-1840 3760);
DISPLAY INVISIBLE (-1840 3760);
FORCEPROP 1 LASTPIN (-1850 3750) BN 0
J 2
(-1838 3758);
DISPLAY 0.680851 (-1838 3758);
PAINT GREEN (-1838 3758);
FORCEPROP 2 LAST CDS_LIB standard
J 0
(-1900 3750);
DISPLAY INVISIBLE (-1900 3750);
FORCEPROP 1 LAST BODY_TYPE PLUMBING
J 2
(-1900 3800);
DISPLAY 0.872340 (-1900 3800);
PAINT GREEN (-1900 3800);
DISPLAY INVISIBLE (-1900 3800);
FORCEPROP 1 LAST HDL_TAP TRUE
J 2
(-2225 3625);
DISPLAY 0.872340 (-2225 3625);
DISPLAY INVISIBLE (-2225 3625);
FORCEPROP 1 LAST PATH I48
J 2
(-1898 3750);
DISPLAY 0.872340 (-1898 3750);
PAINT GREEN (-1898 3750);
DISPLAY INVISIBLE (-1898 3750);
FORCEADD TAP..1
R 2
(-1900 3850);
FORCEPROP 3 LASTPIN (-1850 3850) SIG_NAME M_D_CPU0_SA_CA<2>
J 0
(-1840 3860);
DISPLAY 0.659574 (-1840 3860);
PAINT MONO (-1840 3860);
DISPLAY INVISIBLE (-1840 3860);
FORCEPROP 1 LASTPIN (-1850 3850) BN 2
J 2
(-1838 3858);
DISPLAY 0.680851 (-1838 3858);
PAINT GREEN (-1838 3858);
FORCEPROP 2 LAST CDS_LIB standard
J 0
(-1900 3850);
DISPLAY INVISIBLE (-1900 3850);
FORCEPROP 1 LAST BODY_TYPE PLUMBING
J 2
(-1900 3900);
DISPLAY 0.872340 (-1900 3900);
PAINT GREEN (-1900 3900);
DISPLAY INVISIBLE (-1900 3900);
FORCEPROP 1 LAST HDL_TAP TRUE
J 2
(-2225 3725);
DISPLAY 0.872340 (-2225 3725);
DISPLAY INVISIBLE (-2225 3725);
FORCEPROP 1 LAST PATH I49
J 2
(-1898 3850);
DISPLAY 0.872340 (-1898 3850);
PAINT GREEN (-1898 3850);
DISPLAY INVISIBLE (-1898 3850);
FORCEADD OFFPAGE..2
R 2
(-2825 600);
FORCEPROP 2 LAST $XR0 23 
J 0
(-3049 600);
DISPLAY 0.638298 (-3049 600);
PAINT MONO (-3049 600);
FORCEPROP 2 LAST CDS_LIB standard
J 0
(-2825 600);
PAINT MONO (-2825 600);
DISPLAY INVISIBLE (-2825 600);
FORCEPROP 1 LAST OFFPAGE TRUE
J 2
(-3150 475);
DISPLAY 0.872340 (-3150 475);
DISPLAY INVISIBLE (-3150 475);
FORCEPROP 1 LAST COMMENT_BODY TRUE
J 2
(-2780 505);
DISPLAY 0.872340 (-2780 505);
PAINT GREEN (-2780 505);
DISPLAY INVISIBLE (-2780 505);
FORCEPROP 2 LAST PATH I5
J 0
(-2775 675);
DISPLAY 1.021277 (-2775 675);
DISPLAY INVISIBLE (-2775 675);
FORCEADD TAP..1
R 2
(-1900 3950);
FORCEPROP 3 LASTPIN (-1850 3950) SIG_NAME M_D_CPU0_SA_CA<4>
J 0
(-1840 3960);
DISPLAY 0.659574 (-1840 3960);
PAINT MONO (-1840 3960);
DISPLAY INVISIBLE (-1840 3960);
FORCEPROP 1 LASTPIN (-1850 3950) BN 4
J 2
(-1838 3958);
DISPLAY 0.680851 (-1838 3958);
PAINT GREEN (-1838 3958);
FORCEPROP 2 LAST CDS_LIB standard
J 0
(-1900 3950);
DISPLAY INVISIBLE (-1900 3950);
FORCEPROP 1 LAST BODY_TYPE PLUMBING
J 2
(-1900 4000);
DISPLAY 0.872340 (-1900 4000);
PAINT GREEN (-1900 4000);
DISPLAY INVISIBLE (-1900 4000);
FORCEPROP 1 LAST HDL_TAP TRUE
J 2
(-2225 3825);
DISPLAY 0.872340 (-2225 3825);
DISPLAY INVISIBLE (-2225 3825);
FORCEPROP 1 LAST PATH I50
J 2
(-1898 3950);
DISPLAY 0.872340 (-1898 3950);
PAINT GREEN (-1898 3950);
DISPLAY INVISIBLE (-1898 3950);
FORCEADD TAP..1
R 2
(-1900 3900);
FORCEPROP 3 LASTPIN (-1850 3900) SIG_NAME M_D_CPU0_SA_CA<3>
J 0
(-1840 3910);
DISPLAY 0.659574 (-1840 3910);
PAINT MONO (-1840 3910);
DISPLAY INVISIBLE (-1840 3910);
FORCEPROP 1 LASTPIN (-1850 3900) BN 3
J 2
(-1838 3908);
DISPLAY 0.680851 (-1838 3908);
PAINT GREEN (-1838 3908);
FORCEPROP 2 LAST CDS_LIB standard
J 0
(-1900 3900);
DISPLAY INVISIBLE (-1900 3900);
FORCEPROP 1 LAST BODY_TYPE PLUMBING
J 2
(-1900 3950);
DISPLAY 0.872340 (-1900 3950);
PAINT GREEN (-1900 3950);
DISPLAY INVISIBLE (-1900 3950);
FORCEPROP 1 LAST HDL_TAP TRUE
J 2
(-2225 3775);
DISPLAY 0.872340 (-2225 3775);
DISPLAY INVISIBLE (-2225 3775);
FORCEPROP 1 LAST PATH I51
J 2
(-1898 3900);
DISPLAY 0.872340 (-1898 3900);
PAINT GREEN (-1898 3900);
DISPLAY INVISIBLE (-1898 3900);
FORCEADD TAP..1
(-250 900);
FORCEPROP 3 LASTPIN (-300 900) SIG_NAME M_D_CPU0_SB_DQ<1>
J 0
(-290 910);
DISPLAY 0.659574 (-290 910);
PAINT MONO (-290 910);
DISPLAY INVISIBLE (-290 910);
FORCEPROP 1 LASTPIN (-300 900) BN 1
J 0
(-312 908);
DISPLAY 0.680851 (-312 908);
PAINT GREEN (-312 908);
FORCEPROP 2 LAST CDS_LIB standard
J 0
(-250 900);
PAINT MONO (-250 900);
DISPLAY INVISIBLE (-250 900);
FORCEPROP 1 LAST BODY_TYPE PLUMBING
J 0
(-250 950);
DISPLAY 0.872340 (-250 950);
PAINT GREEN (-250 950);
DISPLAY INVISIBLE (-250 950);
FORCEPROP 1 LAST HDL_TAP TRUE
J 0
(75 775);
DISPLAY 0.872340 (75 775);
DISPLAY INVISIBLE (75 775);
FORCEPROP 1 LAST PATH I52
J 0
(-252 900);
DISPLAY 0.872340 (-252 900);
PAINT GREEN (-252 900);
DISPLAY INVISIBLE (-252 900);
FORCEADD TAP..1
(-250 850);
FORCEPROP 3 LASTPIN (-300 850) SIG_NAME M_D_CPU0_SB_DQ<0>
J 0
(-290 860);
DISPLAY 0.659574 (-290 860);
PAINT MONO (-290 860);
DISPLAY INVISIBLE (-290 860);
FORCEPROP 1 LASTPIN (-300 850) BN 0
J 0
(-312 858);
DISPLAY 0.680851 (-312 858);
PAINT GREEN (-312 858);
FORCEPROP 2 LAST CDS_LIB standard
J 0
(-250 850);
PAINT MONO (-250 850);
DISPLAY INVISIBLE (-250 850);
FORCEPROP 1 LAST BODY_TYPE PLUMBING
J 0
(-250 900);
DISPLAY 0.872340 (-250 900);
PAINT GREEN (-250 900);
DISPLAY INVISIBLE (-250 900);
FORCEPROP 1 LAST HDL_TAP TRUE
J 0
(75 725);
DISPLAY 0.872340 (75 725);
DISPLAY INVISIBLE (75 725);
FORCEPROP 1 LAST PATH I53
J 0
(-252 850);
DISPLAY 0.872340 (-252 850);
PAINT GREEN (-252 850);
DISPLAY INVISIBLE (-252 850);
FORCEADD TAP..1
(-250 950);
FORCEPROP 3 LASTPIN (-300 950) SIG_NAME M_D_CPU0_SB_DQ<2>
J 0
(-290 960);
DISPLAY 0.659574 (-290 960);
PAINT MONO (-290 960);
DISPLAY INVISIBLE (-290 960);
FORCEPROP 1 LASTPIN (-300 950) BN 2
J 0
(-312 958);
DISPLAY 0.680851 (-312 958);
PAINT GREEN (-312 958);
FORCEPROP 2 LAST CDS_LIB standard
J 0
(-250 950);
PAINT MONO (-250 950);
DISPLAY INVISIBLE (-250 950);
FORCEPROP 1 LAST BODY_TYPE PLUMBING
J 0
(-250 1000);
DISPLAY 0.872340 (-250 1000);
PAINT GREEN (-250 1000);
DISPLAY INVISIBLE (-250 1000);
FORCEPROP 1 LAST HDL_TAP TRUE
J 0
(75 825);
DISPLAY 0.872340 (75 825);
DISPLAY INVISIBLE (75 825);
FORCEPROP 1 LAST PATH I54
J 0
(-252 950);
DISPLAY 0.872340 (-252 950);
PAINT GREEN (-252 950);
DISPLAY INVISIBLE (-252 950);
FORCEADD TAP..1
(-250 1050);
FORCEPROP 3 LASTPIN (-300 1050) SIG_NAME M_D_CPU0_SB_DQ<4>
J 0
(-290 1060);
DISPLAY 0.659574 (-290 1060);
PAINT MONO (-290 1060);
DISPLAY INVISIBLE (-290 1060);
FORCEPROP 1 LASTPIN (-300 1050) BN 4
J 0
(-312 1058);
DISPLAY 0.680851 (-312 1058);
PAINT GREEN (-312 1058);
FORCEPROP 2 LAST CDS_LIB standard
J 0
(-250 1050);
PAINT MONO (-250 1050);
DISPLAY INVISIBLE (-250 1050);
FORCEPROP 1 LAST BODY_TYPE PLUMBING
J 0
(-250 1100);
DISPLAY 0.872340 (-250 1100);
PAINT GREEN (-250 1100);
DISPLAY INVISIBLE (-250 1100);
FORCEPROP 1 LAST HDL_TAP TRUE
J 0
(75 925);
DISPLAY 0.872340 (75 925);
DISPLAY INVISIBLE (75 925);
FORCEPROP 1 LAST PATH I55
J 0
(-252 1050);
DISPLAY 0.872340 (-252 1050);
PAINT GREEN (-252 1050);
DISPLAY INVISIBLE (-252 1050);
FORCEADD TAP..1
(-250 1000);
FORCEPROP 3 LASTPIN (-300 1000) SIG_NAME M_D_CPU0_SB_DQ<3>
J 0
(-290 1010);
DISPLAY 0.659574 (-290 1010);
PAINT MONO (-290 1010);
DISPLAY INVISIBLE (-290 1010);
FORCEPROP 1 LASTPIN (-300 1000) BN 3
J 0
(-312 1008);
DISPLAY 0.680851 (-312 1008);
PAINT GREEN (-312 1008);
FORCEPROP 2 LAST CDS_LIB standard
J 0
(-250 1000);
PAINT MONO (-250 1000);
DISPLAY INVISIBLE (-250 1000);
FORCEPROP 1 LAST BODY_TYPE PLUMBING
J 0
(-250 1050);
DISPLAY 0.872340 (-250 1050);
PAINT GREEN (-250 1050);
DISPLAY INVISIBLE (-250 1050);
FORCEPROP 1 LAST HDL_TAP TRUE
J 0
(75 875);
DISPLAY 0.872340 (75 875);
DISPLAY INVISIBLE (75 875);
FORCEPROP 1 LAST PATH I56
J 0
(-252 1000);
DISPLAY 0.872340 (-252 1000);
PAINT GREEN (-252 1000);
DISPLAY INVISIBLE (-252 1000);
FORCEADD TAP..1
(-250 1100);
FORCEPROP 3 LASTPIN (-300 1100) SIG_NAME M_D_CPU0_SB_DQ<5>
J 0
(-290 1110);
DISPLAY 0.659574 (-290 1110);
PAINT MONO (-290 1110);
DISPLAY INVISIBLE (-290 1110);
FORCEPROP 1 LASTPIN (-300 1100) BN 5
J 0
(-312 1108);
DISPLAY 0.680851 (-312 1108);
PAINT GREEN (-312 1108);
FORCEPROP 2 LAST CDS_LIB standard
J 0
(-250 1100);
PAINT MONO (-250 1100);
DISPLAY INVISIBLE (-250 1100);
FORCEPROP 1 LAST BODY_TYPE PLUMBING
J 0
(-250 1150);
DISPLAY 0.872340 (-250 1150);
PAINT GREEN (-250 1150);
DISPLAY INVISIBLE (-250 1150);
FORCEPROP 1 LAST HDL_TAP TRUE
J 0
(75 975);
DISPLAY 0.872340 (75 975);
DISPLAY INVISIBLE (75 975);
FORCEPROP 1 LAST PATH I57
J 0
(-252 1100);
DISPLAY 0.872340 (-252 1100);
PAINT GREEN (-252 1100);
DISPLAY INVISIBLE (-252 1100);
FORCEADD TAP..1
(-250 1150);
FORCEPROP 3 LASTPIN (-300 1150) SIG_NAME M_D_CPU0_SB_DQ<6>
J 0
(-290 1160);
DISPLAY 0.659574 (-290 1160);
PAINT MONO (-290 1160);
DISPLAY INVISIBLE (-290 1160);
FORCEPROP 1 LASTPIN (-300 1150) BN 6
J 0
(-312 1158);
DISPLAY 0.680851 (-312 1158);
PAINT GREEN (-312 1158);
FORCEPROP 2 LAST CDS_LIB standard
J 0
(-250 1150);
PAINT MONO (-250 1150);
DISPLAY INVISIBLE (-250 1150);
FORCEPROP 1 LAST BODY_TYPE PLUMBING
J 0
(-250 1200);
DISPLAY 0.872340 (-250 1200);
PAINT GREEN (-250 1200);
DISPLAY INVISIBLE (-250 1200);
FORCEPROP 1 LAST HDL_TAP TRUE
J 0
(75 1025);
DISPLAY 0.872340 (75 1025);
DISPLAY INVISIBLE (75 1025);
FORCEPROP 1 LAST PATH I58
J 0
(-252 1150);
DISPLAY 0.872340 (-252 1150);
PAINT GREEN (-252 1150);
DISPLAY INVISIBLE (-252 1150);
FORCEADD TAP..1
(-250 1200);
FORCEPROP 3 LASTPIN (-300 1200) SIG_NAME M_D_CPU0_SB_DQ<7>
J 0
(-290 1210);
DISPLAY 0.659574 (-290 1210);
PAINT MONO (-290 1210);
DISPLAY INVISIBLE (-290 1210);
FORCEPROP 1 LASTPIN (-300 1200) BN 7
J 0
(-312 1208);
DISPLAY 0.680851 (-312 1208);
PAINT GREEN (-312 1208);
FORCEPROP 2 LAST CDS_LIB standard
J 0
(-250 1200);
PAINT MONO (-250 1200);
DISPLAY INVISIBLE (-250 1200);
FORCEPROP 1 LAST BODY_TYPE PLUMBING
J 0
(-250 1250);
DISPLAY 0.872340 (-250 1250);
PAINT GREEN (-250 1250);
DISPLAY INVISIBLE (-250 1250);
FORCEPROP 1 LAST HDL_TAP TRUE
J 0
(75 1075);
DISPLAY 0.872340 (75 1075);
DISPLAY INVISIBLE (75 1075);
FORCEPROP 1 LAST PATH I59
J 0
(-252 1200);
DISPLAY 0.872340 (-252 1200);
PAINT GREEN (-252 1200);
DISPLAY INVISIBLE (-252 1200);
FORCEADD TAP..1
(-250 1250);
FORCEPROP 3 LASTPIN (-300 1250) SIG_NAME M_D_CPU0_SB_DQ<8>
J 0
(-290 1260);
DISPLAY 0.659574 (-290 1260);
PAINT MONO (-290 1260);
DISPLAY INVISIBLE (-290 1260);
FORCEPROP 1 LASTPIN (-300 1250) BN 8
J 0
(-312 1258);
DISPLAY 0.680851 (-312 1258);
PAINT GREEN (-312 1258);
FORCEPROP 2 LAST CDS_LIB standard
J 0
(-250 1250);
PAINT MONO (-250 1250);
DISPLAY INVISIBLE (-250 1250);
FORCEPROP 1 LAST BODY_TYPE PLUMBING
J 0
(-250 1300);
DISPLAY 0.872340 (-250 1300);
PAINT GREEN (-250 1300);
DISPLAY INVISIBLE (-250 1300);
FORCEPROP 1 LAST HDL_TAP TRUE
J 0
(75 1125);
DISPLAY 0.872340 (75 1125);
DISPLAY INVISIBLE (75 1125);
FORCEPROP 1 LAST PATH I60
J 0
(-252 1250);
DISPLAY 0.872340 (-252 1250);
PAINT GREEN (-252 1250);
DISPLAY INVISIBLE (-252 1250);
FORCEADD TAP..1
(-250 1300);
FORCEPROP 3 LASTPIN (-300 1300) SIG_NAME M_D_CPU0_SB_DQ<9>
J 0
(-290 1310);
DISPLAY 0.659574 (-290 1310);
PAINT MONO (-290 1310);
DISPLAY INVISIBLE (-290 1310);
FORCEPROP 1 LASTPIN (-300 1300) BN 9
J 0
(-312 1308);
DISPLAY 0.680851 (-312 1308);
PAINT GREEN (-312 1308);
FORCEPROP 2 LAST CDS_LIB standard
J 0
(-250 1300);
PAINT MONO (-250 1300);
DISPLAY INVISIBLE (-250 1300);
FORCEPROP 1 LAST BODY_TYPE PLUMBING
J 0
(-250 1350);
DISPLAY 0.872340 (-250 1350);
PAINT GREEN (-250 1350);
DISPLAY INVISIBLE (-250 1350);
FORCEPROP 1 LAST HDL_TAP TRUE
J 0
(75 1175);
DISPLAY 0.872340 (75 1175);
DISPLAY INVISIBLE (75 1175);
FORCEPROP 1 LAST PATH I61
J 0
(-252 1300);
DISPLAY 0.872340 (-252 1300);
PAINT GREEN (-252 1300);
DISPLAY INVISIBLE (-252 1300);
FORCEADD TAP..1
(-250 1400);
FORCEPROP 3 LASTPIN (-300 1400) SIG_NAME M_D_CPU0_SB_DQ<11>
J 0
(-290 1410);
DISPLAY 0.659574 (-290 1410);
PAINT MONO (-290 1410);
DISPLAY INVISIBLE (-290 1410);
FORCEPROP 1 LASTPIN (-300 1400) BN 11
J 0
(-312 1408);
DISPLAY 0.680851 (-312 1408);
PAINT GREEN (-312 1408);
FORCEPROP 2 LAST CDS_LIB standard
J 0
(-250 1400);
PAINT MONO (-250 1400);
DISPLAY INVISIBLE (-250 1400);
FORCEPROP 1 LAST BODY_TYPE PLUMBING
J 0
(-250 1450);
DISPLAY 0.872340 (-250 1450);
PAINT GREEN (-250 1450);
DISPLAY INVISIBLE (-250 1450);
FORCEPROP 1 LAST HDL_TAP TRUE
J 0
(75 1275);
DISPLAY 0.872340 (75 1275);
DISPLAY INVISIBLE (75 1275);
FORCEPROP 1 LAST PATH I62
J 0
(-252 1400);
DISPLAY 0.872340 (-252 1400);
PAINT GREEN (-252 1400);
DISPLAY INVISIBLE (-252 1400);
FORCEADD TAP..1
(-250 1350);
FORCEPROP 3 LASTPIN (-300 1350) SIG_NAME M_D_CPU0_SB_DQ<10>
J 0
(-290 1360);
DISPLAY 0.659574 (-290 1360);
PAINT MONO (-290 1360);
DISPLAY INVISIBLE (-290 1360);
FORCEPROP 1 LASTPIN (-300 1350) BN 10
J 0
(-312 1358);
DISPLAY 0.680851 (-312 1358);
PAINT GREEN (-312 1358);
FORCEPROP 2 LAST CDS_LIB standard
J 0
(-250 1350);
PAINT MONO (-250 1350);
DISPLAY INVISIBLE (-250 1350);
FORCEPROP 1 LAST BODY_TYPE PLUMBING
J 0
(-250 1400);
DISPLAY 0.872340 (-250 1400);
PAINT GREEN (-250 1400);
DISPLAY INVISIBLE (-250 1400);
FORCEPROP 1 LAST HDL_TAP TRUE
J 0
(75 1225);
DISPLAY 0.872340 (75 1225);
DISPLAY INVISIBLE (75 1225);
FORCEPROP 1 LAST PATH I63
J 0
(-252 1350);
DISPLAY 0.872340 (-252 1350);
PAINT GREEN (-252 1350);
DISPLAY INVISIBLE (-252 1350);
FORCEADD TAP..1
(-250 1450);
FORCEPROP 3 LASTPIN (-300 1450) SIG_NAME M_D_CPU0_SB_DQ<12>
J 0
(-290 1460);
DISPLAY 0.659574 (-290 1460);
PAINT MONO (-290 1460);
DISPLAY INVISIBLE (-290 1460);
FORCEPROP 1 LASTPIN (-300 1450) BN 12
J 0
(-312 1458);
DISPLAY 0.680851 (-312 1458);
PAINT GREEN (-312 1458);
FORCEPROP 2 LAST CDS_LIB standard
J 0
(-250 1450);
PAINT MONO (-250 1450);
DISPLAY INVISIBLE (-250 1450);
FORCEPROP 1 LAST BODY_TYPE PLUMBING
J 0
(-250 1500);
DISPLAY 0.872340 (-250 1500);
PAINT GREEN (-250 1500);
DISPLAY INVISIBLE (-250 1500);
FORCEPROP 1 LAST HDL_TAP TRUE
J 0
(75 1325);
DISPLAY 0.872340 (75 1325);
DISPLAY INVISIBLE (75 1325);
FORCEPROP 1 LAST PATH I64
J 0
(-252 1450);
DISPLAY 0.872340 (-252 1450);
PAINT GREEN (-252 1450);
DISPLAY INVISIBLE (-252 1450);
FORCEADD TAP..1
(-250 1500);
FORCEPROP 3 LASTPIN (-300 1500) SIG_NAME M_D_CPU0_SB_DQ<13>
J 0
(-290 1510);
DISPLAY 0.659574 (-290 1510);
PAINT MONO (-290 1510);
DISPLAY INVISIBLE (-290 1510);
FORCEPROP 1 LASTPIN (-300 1500) BN 13
J 0
(-312 1508);
DISPLAY 0.680851 (-312 1508);
PAINT GREEN (-312 1508);
FORCEPROP 2 LAST CDS_LIB standard
J 0
(-250 1500);
PAINT MONO (-250 1500);
DISPLAY INVISIBLE (-250 1500);
FORCEPROP 1 LAST BODY_TYPE PLUMBING
J 0
(-250 1550);
DISPLAY 0.872340 (-250 1550);
PAINT GREEN (-250 1550);
DISPLAY INVISIBLE (-250 1550);
FORCEPROP 1 LAST HDL_TAP TRUE
J 0
(75 1375);
DISPLAY 0.872340 (75 1375);
DISPLAY INVISIBLE (75 1375);
FORCEPROP 1 LAST PATH I65
J 0
(-252 1500);
DISPLAY 0.872340 (-252 1500);
PAINT GREEN (-252 1500);
DISPLAY INVISIBLE (-252 1500);
FORCEADD TAP..1
(-250 1550);
FORCEPROP 3 LASTPIN (-300 1550) SIG_NAME M_D_CPU0_SB_DQ<14>
J 0
(-290 1560);
DISPLAY 0.659574 (-290 1560);
PAINT MONO (-290 1560);
DISPLAY INVISIBLE (-290 1560);
FORCEPROP 1 LASTPIN (-300 1550) BN 14
J 0
(-312 1558);
DISPLAY 0.680851 (-312 1558);
PAINT GREEN (-312 1558);
FORCEPROP 2 LAST CDS_LIB standard
J 0
(-250 1550);
PAINT MONO (-250 1550);
DISPLAY INVISIBLE (-250 1550);
FORCEPROP 1 LAST BODY_TYPE PLUMBING
J 0
(-250 1600);
DISPLAY 0.872340 (-250 1600);
PAINT GREEN (-250 1600);
DISPLAY INVISIBLE (-250 1600);
FORCEPROP 1 LAST HDL_TAP TRUE
J 0
(75 1425);
DISPLAY 0.872340 (75 1425);
DISPLAY INVISIBLE (75 1425);
FORCEPROP 1 LAST PATH I66
J 0
(-252 1550);
DISPLAY 0.872340 (-252 1550);
PAINT GREEN (-252 1550);
DISPLAY INVISIBLE (-252 1550);
FORCEADD TAP..1
(-250 1600);
FORCEPROP 3 LASTPIN (-300 1600) SIG_NAME M_D_CPU0_SB_DQ<15>
J 0
(-290 1610);
DISPLAY 0.659574 (-290 1610);
PAINT MONO (-290 1610);
DISPLAY INVISIBLE (-290 1610);
FORCEPROP 1 LASTPIN (-300 1600) BN 15
J 0
(-312 1608);
DISPLAY 0.680851 (-312 1608);
PAINT GREEN (-312 1608);
FORCEPROP 2 LAST CDS_LIB standard
J 0
(-250 1600);
PAINT MONO (-250 1600);
DISPLAY INVISIBLE (-250 1600);
FORCEPROP 1 LAST BODY_TYPE PLUMBING
J 0
(-250 1650);
DISPLAY 0.872340 (-250 1650);
PAINT GREEN (-250 1650);
DISPLAY INVISIBLE (-250 1650);
FORCEPROP 1 LAST HDL_TAP TRUE
J 0
(75 1475);
DISPLAY 0.872340 (75 1475);
DISPLAY INVISIBLE (75 1475);
FORCEPROP 1 LAST PATH I67
J 0
(-252 1600);
DISPLAY 0.872340 (-252 1600);
PAINT GREEN (-252 1600);
DISPLAY INVISIBLE (-252 1600);
FORCEADD TAP..1
(-250 1650);
FORCEPROP 3 LASTPIN (-300 1650) SIG_NAME M_D_CPU0_SB_DQ<16>
J 0
(-290 1660);
DISPLAY 0.659574 (-290 1660);
PAINT MONO (-290 1660);
DISPLAY INVISIBLE (-290 1660);
FORCEPROP 1 LASTPIN (-300 1650) BN 16
J 0
(-312 1658);
DISPLAY 0.680851 (-312 1658);
PAINT GREEN (-312 1658);
FORCEPROP 2 LAST CDS_LIB standard
J 0
(-250 1650);
PAINT MONO (-250 1650);
DISPLAY INVISIBLE (-250 1650);
FORCEPROP 1 LAST BODY_TYPE PLUMBING
J 0
(-250 1700);
DISPLAY 0.872340 (-250 1700);
PAINT GREEN (-250 1700);
DISPLAY INVISIBLE (-250 1700);
FORCEPROP 1 LAST HDL_TAP TRUE
J 0
(75 1525);
DISPLAY 0.872340 (75 1525);
DISPLAY INVISIBLE (75 1525);
FORCEPROP 1 LAST PATH I68
J 0
(-252 1650);
DISPLAY 0.872340 (-252 1650);
PAINT GREEN (-252 1650);
DISPLAY INVISIBLE (-252 1650);
FORCEADD TAP..1
(-250 1700);
FORCEPROP 3 LASTPIN (-300 1700) SIG_NAME M_D_CPU0_SB_DQ<17>
J 0
(-290 1710);
DISPLAY 0.659574 (-290 1710);
PAINT MONO (-290 1710);
DISPLAY INVISIBLE (-290 1710);
FORCEPROP 1 LASTPIN (-300 1700) BN 17
J 0
(-312 1708);
DISPLAY 0.680851 (-312 1708);
PAINT GREEN (-312 1708);
FORCEPROP 2 LAST CDS_LIB standard
J 0
(-250 1700);
PAINT MONO (-250 1700);
DISPLAY INVISIBLE (-250 1700);
FORCEPROP 1 LAST BODY_TYPE PLUMBING
J 0
(-250 1750);
DISPLAY 0.872340 (-250 1750);
PAINT GREEN (-250 1750);
DISPLAY INVISIBLE (-250 1750);
FORCEPROP 1 LAST HDL_TAP TRUE
J 0
(75 1575);
DISPLAY 0.872340 (75 1575);
DISPLAY INVISIBLE (75 1575);
FORCEPROP 1 LAST PATH I69
J 0
(-252 1700);
DISPLAY 0.872340 (-252 1700);
PAINT GREEN (-252 1700);
DISPLAY INVISIBLE (-252 1700);
FORCEADD OFFPAGE..1
(-2825 1700);
FORCEPROP 2 LAST $XR1 89 
J 0
(-3136 1700);
DISPLAY 0.638298 (-3136 1700);
PAINT MONO (-3136 1700);
FORCEPROP 2 LAST $XR0 23 
J 0
(-3046 1700);
DISPLAY 0.638298 (-3046 1700);
PAINT MONO (-3046 1700);
FORCEPROP 2 LAST CDS_LIB standard
J 0
(-2825 1700);
PAINT MONO (-2825 1700);
DISPLAY INVISIBLE (-2825 1700);
FORCEPROP 1 LAST OFFPAGE TRUE
J 0
(-2500 1575);
DISPLAY 0.872340 (-2500 1575);
DISPLAY INVISIBLE (-2500 1575);
FORCEPROP 1 LAST COMMENT_BODY TRUE
J 0
(-2700 1600);
DISPLAY 0.872340 (-2700 1600);
PAINT GREEN (-2700 1600);
DISPLAY INVISIBLE (-2700 1600);
FORCEPROP 2 LAST PATH I7
J 0
(-2775 1775);
DISPLAY 1.021277 (-2775 1775);
DISPLAY INVISIBLE (-2775 1775);
FORCEADD TAP..1
(-250 1750);
FORCEPROP 3 LASTPIN (-300 1750) SIG_NAME M_D_CPU0_SB_DQ<18>
J 0
(-290 1760);
DISPLAY 0.659574 (-290 1760);
PAINT MONO (-290 1760);
DISPLAY INVISIBLE (-290 1760);
FORCEPROP 1 LASTPIN (-300 1750) BN 18
J 0
(-312 1758);
DISPLAY 0.680851 (-312 1758);
PAINT GREEN (-312 1758);
FORCEPROP 2 LAST CDS_LIB standard
J 0
(-250 1750);
PAINT MONO (-250 1750);
DISPLAY INVISIBLE (-250 1750);
FORCEPROP 1 LAST BODY_TYPE PLUMBING
J 0
(-250 1800);
DISPLAY 0.872340 (-250 1800);
PAINT GREEN (-250 1800);
DISPLAY INVISIBLE (-250 1800);
FORCEPROP 1 LAST HDL_TAP TRUE
J 0
(75 1625);
DISPLAY 0.872340 (75 1625);
DISPLAY INVISIBLE (75 1625);
FORCEPROP 1 LAST PATH I70
J 0
(-252 1750);
DISPLAY 0.872340 (-252 1750);
PAINT GREEN (-252 1750);
DISPLAY INVISIBLE (-252 1750);
FORCEADD TAP..1
(-250 1800);
FORCEPROP 3 LASTPIN (-300 1800) SIG_NAME M_D_CPU0_SB_DQ<19>
J 0
(-290 1810);
DISPLAY 0.659574 (-290 1810);
PAINT MONO (-290 1810);
DISPLAY INVISIBLE (-290 1810);
FORCEPROP 1 LASTPIN (-300 1800) BN 19
J 0
(-312 1808);
DISPLAY 0.680851 (-312 1808);
PAINT GREEN (-312 1808);
FORCEPROP 2 LAST CDS_LIB standard
J 0
(-250 1800);
PAINT MONO (-250 1800);
DISPLAY INVISIBLE (-250 1800);
FORCEPROP 1 LAST BODY_TYPE PLUMBING
J 0
(-250 1850);
DISPLAY 0.872340 (-250 1850);
PAINT GREEN (-250 1850);
DISPLAY INVISIBLE (-250 1850);
FORCEPROP 1 LAST HDL_TAP TRUE
J 0
(75 1675);
DISPLAY 0.872340 (75 1675);
DISPLAY INVISIBLE (75 1675);
FORCEPROP 1 LAST PATH I71
J 0
(-252 1800);
DISPLAY 0.872340 (-252 1800);
PAINT GREEN (-252 1800);
DISPLAY INVISIBLE (-252 1800);
FORCEADD TAP..1
(-250 1900);
FORCEPROP 3 LASTPIN (-300 1900) SIG_NAME M_D_CPU0_SB_DQ<21>
J 0
(-290 1910);
DISPLAY 0.659574 (-290 1910);
PAINT MONO (-290 1910);
DISPLAY INVISIBLE (-290 1910);
FORCEPROP 1 LASTPIN (-300 1900) BN 21
J 0
(-312 1908);
DISPLAY 0.680851 (-312 1908);
PAINT GREEN (-312 1908);
FORCEPROP 2 LAST CDS_LIB standard
J 0
(-250 1900);
PAINT MONO (-250 1900);
DISPLAY INVISIBLE (-250 1900);
FORCEPROP 1 LAST BODY_TYPE PLUMBING
J 0
(-250 1950);
DISPLAY 0.872340 (-250 1950);
PAINT GREEN (-250 1950);
DISPLAY INVISIBLE (-250 1950);
FORCEPROP 1 LAST HDL_TAP TRUE
J 0
(75 1775);
DISPLAY 0.872340 (75 1775);
DISPLAY INVISIBLE (75 1775);
FORCEPROP 1 LAST PATH I72
J 0
(-252 1900);
DISPLAY 0.872340 (-252 1900);
PAINT GREEN (-252 1900);
DISPLAY INVISIBLE (-252 1900);
FORCEADD TAP..1
(-250 1850);
FORCEPROP 3 LASTPIN (-300 1850) SIG_NAME M_D_CPU0_SB_DQ<20>
J 0
(-290 1860);
DISPLAY 0.659574 (-290 1860);
PAINT MONO (-290 1860);
DISPLAY INVISIBLE (-290 1860);
FORCEPROP 1 LASTPIN (-300 1850) BN 20
J 0
(-312 1858);
DISPLAY 0.680851 (-312 1858);
PAINT GREEN (-312 1858);
FORCEPROP 2 LAST CDS_LIB standard
J 0
(-250 1850);
PAINT MONO (-250 1850);
DISPLAY INVISIBLE (-250 1850);
FORCEPROP 1 LAST BODY_TYPE PLUMBING
J 0
(-250 1900);
DISPLAY 0.872340 (-250 1900);
PAINT GREEN (-250 1900);
DISPLAY INVISIBLE (-250 1900);
FORCEPROP 1 LAST HDL_TAP TRUE
J 0
(75 1725);
DISPLAY 0.872340 (75 1725);
DISPLAY INVISIBLE (75 1725);
FORCEPROP 1 LAST PATH I73
J 0
(-252 1850);
DISPLAY 0.872340 (-252 1850);
PAINT GREEN (-252 1850);
DISPLAY INVISIBLE (-252 1850);
FORCEADD TAP..1
(-250 1950);
FORCEPROP 3 LASTPIN (-300 1950) SIG_NAME M_D_CPU0_SB_DQ<22>
J 0
(-290 1960);
DISPLAY 0.659574 (-290 1960);
PAINT MONO (-290 1960);
DISPLAY INVISIBLE (-290 1960);
FORCEPROP 1 LASTPIN (-300 1950) BN 22
J 0
(-312 1958);
DISPLAY 0.680851 (-312 1958);
PAINT GREEN (-312 1958);
FORCEPROP 2 LAST CDS_LIB standard
J 0
(-250 1950);
DISPLAY INVISIBLE (-250 1950);
FORCEPROP 1 LAST BODY_TYPE PLUMBING
J 0
(-250 2000);
DISPLAY 0.872340 (-250 2000);
PAINT GREEN (-250 2000);
DISPLAY INVISIBLE (-250 2000);
FORCEPROP 1 LAST HDL_TAP TRUE
J 0
(75 1825);
DISPLAY 0.872340 (75 1825);
DISPLAY INVISIBLE (75 1825);
FORCEPROP 1 LAST PATH I74
J 0
(-252 1950);
DISPLAY 0.872340 (-252 1950);
PAINT GREEN (-252 1950);
DISPLAY INVISIBLE (-252 1950);
FORCEADD TAP..1
(-250 2000);
FORCEPROP 3 LASTPIN (-300 2000) SIG_NAME M_D_CPU0_SB_DQ<23>
J 0
(-290 2010);
DISPLAY 0.659574 (-290 2010);
PAINT MONO (-290 2010);
DISPLAY INVISIBLE (-290 2010);
FORCEPROP 1 LASTPIN (-300 2000) BN 23
J 0
(-312 2008);
DISPLAY 0.680851 (-312 2008);
PAINT GREEN (-312 2008);
FORCEPROP 2 LAST CDS_LIB standard
J 0
(-250 2000);
DISPLAY INVISIBLE (-250 2000);
FORCEPROP 1 LAST BODY_TYPE PLUMBING
J 0
(-250 2050);
DISPLAY 0.872340 (-250 2050);
PAINT GREEN (-250 2050);
DISPLAY INVISIBLE (-250 2050);
FORCEPROP 1 LAST HDL_TAP TRUE
J 0
(75 1875);
DISPLAY 0.872340 (75 1875);
DISPLAY INVISIBLE (75 1875);
FORCEPROP 1 LAST PATH I75
J 0
(-252 2000);
DISPLAY 0.872340 (-252 2000);
PAINT GREEN (-252 2000);
DISPLAY INVISIBLE (-252 2000);
FORCEADD TAP..1
(-250 2050);
FORCEPROP 3 LASTPIN (-300 2050) SIG_NAME M_D_CPU0_SB_DQ<24>
J 0
(-290 2060);
DISPLAY 0.659574 (-290 2060);
PAINT MONO (-290 2060);
DISPLAY INVISIBLE (-290 2060);
FORCEPROP 1 LASTPIN (-300 2050) BN 24
J 0
(-312 2058);
DISPLAY 0.680851 (-312 2058);
PAINT GREEN (-312 2058);
FORCEPROP 2 LAST CDS_LIB standard
J 0
(-250 2050);
DISPLAY INVISIBLE (-250 2050);
FORCEPROP 1 LAST BODY_TYPE PLUMBING
J 0
(-250 2100);
DISPLAY 0.872340 (-250 2100);
PAINT GREEN (-250 2100);
DISPLAY INVISIBLE (-250 2100);
FORCEPROP 1 LAST HDL_TAP TRUE
J 0
(75 1925);
DISPLAY 0.872340 (75 1925);
DISPLAY INVISIBLE (75 1925);
FORCEPROP 1 LAST PATH I76
J 0
(-252 2050);
DISPLAY 0.872340 (-252 2050);
PAINT GREEN (-252 2050);
DISPLAY INVISIBLE (-252 2050);
FORCEADD TAP..1
(-250 2100);
FORCEPROP 3 LASTPIN (-300 2100) SIG_NAME M_D_CPU0_SB_DQ<25>
J 0
(-290 2110);
DISPLAY 0.659574 (-290 2110);
PAINT MONO (-290 2110);
DISPLAY INVISIBLE (-290 2110);
FORCEPROP 1 LASTPIN (-300 2100) BN 25
J 0
(-312 2108);
DISPLAY 0.680851 (-312 2108);
PAINT GREEN (-312 2108);
FORCEPROP 2 LAST CDS_LIB standard
J 0
(-250 2100);
DISPLAY INVISIBLE (-250 2100);
FORCEPROP 1 LAST BODY_TYPE PLUMBING
J 0
(-250 2150);
DISPLAY 0.872340 (-250 2150);
PAINT GREEN (-250 2150);
DISPLAY INVISIBLE (-250 2150);
FORCEPROP 1 LAST HDL_TAP TRUE
J 0
(75 1975);
DISPLAY 0.872340 (75 1975);
DISPLAY INVISIBLE (75 1975);
FORCEPROP 1 LAST PATH I77
J 0
(-252 2100);
DISPLAY 0.872340 (-252 2100);
PAINT GREEN (-252 2100);
DISPLAY INVISIBLE (-252 2100);
FORCEADD TAP..1
(-250 2200);
FORCEPROP 3 LASTPIN (-300 2200) SIG_NAME M_D_CPU0_SB_DQ<27>
J 0
(-290 2210);
DISPLAY 0.659574 (-290 2210);
PAINT MONO (-290 2210);
DISPLAY INVISIBLE (-290 2210);
FORCEPROP 1 LASTPIN (-300 2200) BN 27
J 0
(-312 2208);
DISPLAY 0.680851 (-312 2208);
PAINT GREEN (-312 2208);
FORCEPROP 2 LAST CDS_LIB standard
J 0
(-250 2200);
DISPLAY INVISIBLE (-250 2200);
FORCEPROP 1 LAST BODY_TYPE PLUMBING
J 0
(-250 2250);
DISPLAY 0.872340 (-250 2250);
PAINT GREEN (-250 2250);
DISPLAY INVISIBLE (-250 2250);
FORCEPROP 1 LAST HDL_TAP TRUE
J 0
(75 2075);
DISPLAY 0.872340 (75 2075);
DISPLAY INVISIBLE (75 2075);
FORCEPROP 1 LAST PATH I78
J 0
(-252 2200);
DISPLAY 0.872340 (-252 2200);
PAINT GREEN (-252 2200);
DISPLAY INVISIBLE (-252 2200);
FORCEADD TAP..1
(-250 2150);
FORCEPROP 3 LASTPIN (-300 2150) SIG_NAME M_D_CPU0_SB_DQ<26>
J 0
(-290 2160);
DISPLAY 0.659574 (-290 2160);
PAINT MONO (-290 2160);
DISPLAY INVISIBLE (-290 2160);
FORCEPROP 1 LASTPIN (-300 2150) BN 26
J 0
(-312 2158);
DISPLAY 0.680851 (-312 2158);
PAINT GREEN (-312 2158);
FORCEPROP 2 LAST CDS_LIB standard
J 0
(-250 2150);
DISPLAY INVISIBLE (-250 2150);
FORCEPROP 1 LAST BODY_TYPE PLUMBING
J 0
(-250 2200);
DISPLAY 0.872340 (-250 2200);
PAINT GREEN (-250 2200);
DISPLAY INVISIBLE (-250 2200);
FORCEPROP 1 LAST HDL_TAP TRUE
J 0
(75 2025);
DISPLAY 0.872340 (75 2025);
DISPLAY INVISIBLE (75 2025);
FORCEPROP 1 LAST PATH I79
J 0
(-252 2150);
DISPLAY 0.872340 (-252 2150);
PAINT GREEN (-252 2150);
DISPLAY INVISIBLE (-252 2150);
FORCEADD OFFPAGE..1
(-2725 1550);
FORCEPROP 2 LAST $XR0 88 
J 0
(-2976 1550);
DISPLAY 0.638298 (-2976 1550);
PAINT MONO (-2976 1550);
FORCEPROP 2 LAST CDS_LIB standard
J 0
(-2725 1550);
PAINT MONO (-2725 1550);
DISPLAY INVISIBLE (-2725 1550);
FORCEPROP 1 LAST OFFPAGE TRUE
J 0
(-2400 1425);
DISPLAY 0.872340 (-2400 1425);
DISPLAY INVISIBLE (-2400 1425);
FORCEPROP 1 LAST COMMENT_BODY TRUE
J 0
(-2600 1450);
DISPLAY 0.872340 (-2600 1450);
PAINT GREEN (-2600 1450);
DISPLAY INVISIBLE (-2600 1450);
FORCEPROP 2 LAST PATH I8
J 0
(-2675 1625);
DISPLAY 1.021277 (-2675 1625);
DISPLAY INVISIBLE (-2675 1625);
FORCEADD TAP..1
(-250 2250);
FORCEPROP 3 LASTPIN (-300 2250) SIG_NAME M_D_CPU0_SB_DQ<28>
J 0
(-290 2260);
DISPLAY 0.659574 (-290 2260);
PAINT MONO (-290 2260);
DISPLAY INVISIBLE (-290 2260);
FORCEPROP 1 LASTPIN (-300 2250) BN 28
J 0
(-312 2258);
DISPLAY 0.680851 (-312 2258);
PAINT GREEN (-312 2258);
FORCEPROP 2 LAST CDS_LIB standard
J 0
(-250 2250);
DISPLAY INVISIBLE (-250 2250);
FORCEPROP 1 LAST BODY_TYPE PLUMBING
J 0
(-250 2300);
DISPLAY 0.872340 (-250 2300);
PAINT GREEN (-250 2300);
DISPLAY INVISIBLE (-250 2300);
FORCEPROP 1 LAST HDL_TAP TRUE
J 0
(75 2125);
DISPLAY 0.872340 (75 2125);
DISPLAY INVISIBLE (75 2125);
FORCEPROP 1 LAST PATH I80
J 0
(-252 2250);
DISPLAY 0.872340 (-252 2250);
PAINT GREEN (-252 2250);
DISPLAY INVISIBLE (-252 2250);
FORCEADD TAP..1
(-250 2300);
FORCEPROP 3 LASTPIN (-300 2300) SIG_NAME M_D_CPU0_SB_DQ<29>
J 0
(-290 2310);
DISPLAY 0.659574 (-290 2310);
PAINT MONO (-290 2310);
DISPLAY INVISIBLE (-290 2310);
FORCEPROP 1 LASTPIN (-300 2300) BN 29
J 0
(-312 2308);
DISPLAY 0.680851 (-312 2308);
PAINT GREEN (-312 2308);
FORCEPROP 2 LAST CDS_LIB standard
J 0
(-250 2300);
DISPLAY INVISIBLE (-250 2300);
FORCEPROP 1 LAST BODY_TYPE PLUMBING
J 0
(-250 2350);
DISPLAY 0.872340 (-250 2350);
PAINT GREEN (-250 2350);
DISPLAY INVISIBLE (-250 2350);
FORCEPROP 1 LAST HDL_TAP TRUE
J 0
(75 2175);
DISPLAY 0.872340 (75 2175);
DISPLAY INVISIBLE (75 2175);
FORCEPROP 1 LAST PATH I81
J 0
(-252 2300);
DISPLAY 0.872340 (-252 2300);
PAINT GREEN (-252 2300);
DISPLAY INVISIBLE (-252 2300);
FORCEADD TAP..1
(-250 2400);
FORCEPROP 3 LASTPIN (-300 2400) SIG_NAME M_D_CPU0_SB_DQ<31>
J 0
(-290 2410);
DISPLAY 0.659574 (-290 2410);
PAINT MONO (-290 2410);
DISPLAY INVISIBLE (-290 2410);
FORCEPROP 1 LASTPIN (-300 2400) BN 31
J 0
(-312 2408);
DISPLAY 0.680851 (-312 2408);
PAINT GREEN (-312 2408);
FORCEPROP 2 LAST CDS_LIB standard
J 0
(-250 2400);
DISPLAY INVISIBLE (-250 2400);
FORCEPROP 1 LAST BODY_TYPE PLUMBING
J 0
(-250 2450);
DISPLAY 0.872340 (-250 2450);
PAINT GREEN (-250 2450);
DISPLAY INVISIBLE (-250 2450);
FORCEPROP 1 LAST HDL_TAP TRUE
J 0
(75 2275);
DISPLAY 0.872340 (75 2275);
DISPLAY INVISIBLE (75 2275);
FORCEPROP 1 LAST PATH I82
J 0
(-252 2400);
DISPLAY 0.872340 (-252 2400);
PAINT GREEN (-252 2400);
DISPLAY INVISIBLE (-252 2400);
FORCEADD TAP..1
(-250 2350);
FORCEPROP 3 LASTPIN (-300 2350) SIG_NAME M_D_CPU0_SB_DQ<30>
J 0
(-290 2360);
DISPLAY 0.659574 (-290 2360);
PAINT MONO (-290 2360);
DISPLAY INVISIBLE (-290 2360);
FORCEPROP 1 LASTPIN (-300 2350) BN 30
J 0
(-312 2358);
DISPLAY 0.680851 (-312 2358);
PAINT GREEN (-312 2358);
FORCEPROP 2 LAST CDS_LIB standard
J 0
(-250 2350);
DISPLAY INVISIBLE (-250 2350);
FORCEPROP 1 LAST BODY_TYPE PLUMBING
J 0
(-250 2400);
DISPLAY 0.872340 (-250 2400);
PAINT GREEN (-250 2400);
DISPLAY INVISIBLE (-250 2400);
FORCEPROP 1 LAST HDL_TAP TRUE
J 0
(75 2225);
DISPLAY 0.872340 (75 2225);
DISPLAY INVISIBLE (75 2225);
FORCEPROP 1 LAST PATH I83
J 0
(-252 2350);
DISPLAY 0.872340 (-252 2350);
PAINT GREEN (-252 2350);
DISPLAY INVISIBLE (-252 2350);
FORCEADD TAP..1
(-250 2500);
FORCEPROP 3 LASTPIN (-300 2500) SIG_NAME M_D_CPU0_SA_DQ<0>
J 0
(-290 2510);
DISPLAY 0.659574 (-290 2510);
PAINT MONO (-290 2510);
DISPLAY INVISIBLE (-290 2510);
FORCEPROP 1 LASTPIN (-300 2500) BN 0
J 0
(-312 2508);
DISPLAY 0.680851 (-312 2508);
PAINT GREEN (-312 2508);
FORCEPROP 2 LAST CDS_LIB standard
J 0
(-250 2500);
PAINT MONO (-250 2500);
DISPLAY INVISIBLE (-250 2500);
FORCEPROP 1 LAST BODY_TYPE PLUMBING
J 0
(-250 2550);
DISPLAY 0.872340 (-250 2550);
PAINT GREEN (-250 2550);
DISPLAY INVISIBLE (-250 2550);
FORCEPROP 1 LAST HDL_TAP TRUE
J 0
(75 2375);
DISPLAY 0.872340 (75 2375);
DISPLAY INVISIBLE (75 2375);
FORCEPROP 1 LAST PATH I84
J 0
(-252 2500);
DISPLAY 0.872340 (-252 2500);
PAINT GREEN (-252 2500);
DISPLAY INVISIBLE (-252 2500);
FORCEADD TAP..1
(-250 2550);
FORCEPROP 3 LASTPIN (-300 2550) SIG_NAME M_D_CPU0_SA_DQ<1>
J 0
(-290 2560);
DISPLAY 0.659574 (-290 2560);
PAINT MONO (-290 2560);
DISPLAY INVISIBLE (-290 2560);
FORCEPROP 1 LASTPIN (-300 2550) BN 1
J 0
(-312 2558);
DISPLAY 0.680851 (-312 2558);
PAINT GREEN (-312 2558);
FORCEPROP 2 LAST CDS_LIB standard
J 0
(-250 2550);
PAINT MONO (-250 2550);
DISPLAY INVISIBLE (-250 2550);
FORCEPROP 1 LAST BODY_TYPE PLUMBING
J 0
(-250 2600);
DISPLAY 0.872340 (-250 2600);
PAINT GREEN (-250 2600);
DISPLAY INVISIBLE (-250 2600);
FORCEPROP 1 LAST HDL_TAP TRUE
J 0
(75 2425);
DISPLAY 0.872340 (75 2425);
DISPLAY INVISIBLE (75 2425);
FORCEPROP 1 LAST PATH I85
J 0
(-252 2550);
DISPLAY 0.872340 (-252 2550);
PAINT GREEN (-252 2550);
DISPLAY INVISIBLE (-252 2550);
FORCEADD TAP..1
(-250 2600);
FORCEPROP 3 LASTPIN (-300 2600) SIG_NAME M_D_CPU0_SA_DQ<2>
J 0
(-290 2610);
DISPLAY 0.659574 (-290 2610);
PAINT MONO (-290 2610);
DISPLAY INVISIBLE (-290 2610);
FORCEPROP 1 LASTPIN (-300 2600) BN 2
J 0
(-312 2608);
DISPLAY 0.680851 (-312 2608);
PAINT GREEN (-312 2608);
FORCEPROP 2 LAST CDS_LIB standard
J 0
(-250 2600);
PAINT MONO (-250 2600);
DISPLAY INVISIBLE (-250 2600);
FORCEPROP 1 LAST BODY_TYPE PLUMBING
J 0
(-250 2650);
DISPLAY 0.872340 (-250 2650);
PAINT GREEN (-250 2650);
DISPLAY INVISIBLE (-250 2650);
FORCEPROP 1 LAST HDL_TAP TRUE
J 0
(75 2475);
DISPLAY 0.872340 (75 2475);
DISPLAY INVISIBLE (75 2475);
FORCEPROP 1 LAST PATH I86
J 0
(-252 2600);
DISPLAY 0.872340 (-252 2600);
PAINT GREEN (-252 2600);
DISPLAY INVISIBLE (-252 2600);
FORCEADD TAP..1
(-250 2650);
FORCEPROP 3 LASTPIN (-300 2650) SIG_NAME M_D_CPU0_SA_DQ<3>
J 0
(-290 2660);
DISPLAY 0.659574 (-290 2660);
PAINT MONO (-290 2660);
DISPLAY INVISIBLE (-290 2660);
FORCEPROP 1 LASTPIN (-300 2650) BN 3
J 0
(-312 2658);
DISPLAY 0.680851 (-312 2658);
PAINT GREEN (-312 2658);
FORCEPROP 2 LAST CDS_LIB standard
J 0
(-250 2650);
PAINT MONO (-250 2650);
DISPLAY INVISIBLE (-250 2650);
FORCEPROP 1 LAST BODY_TYPE PLUMBING
J 0
(-250 2700);
DISPLAY 0.872340 (-250 2700);
PAINT GREEN (-250 2700);
DISPLAY INVISIBLE (-250 2700);
FORCEPROP 1 LAST HDL_TAP TRUE
J 0
(75 2525);
DISPLAY 0.872340 (75 2525);
DISPLAY INVISIBLE (75 2525);
FORCEPROP 1 LAST PATH I87
J 0
(-252 2650);
DISPLAY 0.872340 (-252 2650);
PAINT GREEN (-252 2650);
DISPLAY INVISIBLE (-252 2650);
FORCEADD TAP..1
(-250 2700);
FORCEPROP 3 LASTPIN (-300 2700) SIG_NAME M_D_CPU0_SA_DQ<4>
J 0
(-290 2710);
DISPLAY 0.659574 (-290 2710);
PAINT MONO (-290 2710);
DISPLAY INVISIBLE (-290 2710);
FORCEPROP 1 LASTPIN (-300 2700) BN 4
J 0
(-312 2708);
DISPLAY 0.680851 (-312 2708);
PAINT GREEN (-312 2708);
FORCEPROP 2 LAST CDS_LIB standard
J 0
(-250 2700);
PAINT MONO (-250 2700);
DISPLAY INVISIBLE (-250 2700);
FORCEPROP 1 LAST BODY_TYPE PLUMBING
J 0
(-250 2750);
DISPLAY 0.872340 (-250 2750);
PAINT GREEN (-250 2750);
DISPLAY INVISIBLE (-250 2750);
FORCEPROP 1 LAST HDL_TAP TRUE
J 0
(75 2575);
DISPLAY 0.872340 (75 2575);
DISPLAY INVISIBLE (75 2575);
FORCEPROP 1 LAST PATH I88
J 0
(-252 2700);
DISPLAY 0.872340 (-252 2700);
PAINT GREEN (-252 2700);
DISPLAY INVISIBLE (-252 2700);
FORCEADD TAP..1
(-250 2750);
FORCEPROP 3 LASTPIN (-300 2750) SIG_NAME M_D_CPU0_SA_DQ<5>
J 0
(-290 2760);
DISPLAY 0.659574 (-290 2760);
PAINT MONO (-290 2760);
DISPLAY INVISIBLE (-290 2760);
FORCEPROP 1 LASTPIN (-300 2750) BN 5
J 0
(-312 2758);
DISPLAY 0.680851 (-312 2758);
PAINT GREEN (-312 2758);
FORCEPROP 2 LAST CDS_LIB standard
J 0
(-250 2750);
PAINT MONO (-250 2750);
DISPLAY INVISIBLE (-250 2750);
FORCEPROP 1 LAST BODY_TYPE PLUMBING
J 0
(-250 2800);
DISPLAY 0.872340 (-250 2800);
PAINT GREEN (-250 2800);
DISPLAY INVISIBLE (-250 2800);
FORCEPROP 1 LAST HDL_TAP TRUE
J 0
(75 2625);
DISPLAY 0.872340 (75 2625);
DISPLAY INVISIBLE (75 2625);
FORCEPROP 1 LAST PATH I89
J 0
(-252 2750);
DISPLAY 0.872340 (-252 2750);
PAINT GREEN (-252 2750);
DISPLAY INVISIBLE (-252 2750);
FORCEADD OFFPAGE..1
(-2725 1500);
FORCEPROP 2 LAST $XR7 89 
J 0
(-3247 1464);
DISPLAY 0.638298 (-3247 1464);
PAINT MONO (-3247 1464);
FORCEPROP 2 LAST $XR6 87 
J 0
(-3157 1464);
DISPLAY 0.638298 (-3157 1464);
PAINT MONO (-3157 1464);
FORCEPROP 2 LAST $XR5 86 
J 0
(-3067 1464);
DISPLAY 0.638298 (-3067 1464);
PAINT MONO (-3067 1464);
FORCEPROP 2 LAST $XR4 85 
J 0
(-2977 1464);
DISPLAY 0.638298 (-2977 1464);
PAINT MONO (-2977 1464);
FORCEPROP 2 LAST $XR3 84 
J 0
(-3247 1500);
DISPLAY 0.638298 (-3247 1500);
PAINT MONO (-3247 1500);
FORCEPROP 2 LAST $XR2 83 
J 0
(-3157 1500);
DISPLAY 0.638298 (-3157 1500);
PAINT MONO (-3157 1500);
FORCEPROP 2 LAST $XR1 82 
J 0
(-3067 1500);
DISPLAY 0.638298 (-3067 1500);
PAINT MONO (-3067 1500);
FORCEPROP 2 LAST $XR0 229 
J 0
(-2977 1500);
DISPLAY 0.638298 (-2977 1500);
PAINT MONO (-2977 1500);
FORCEPROP 2 LAST CDS_LIB standard
J 0
(-2725 1500);
PAINT MONO (-2725 1500);
DISPLAY INVISIBLE (-2725 1500);
FORCEPROP 1 LAST OFFPAGE TRUE
J 0
(-2400 1375);
DISPLAY 0.872340 (-2400 1375);
DISPLAY INVISIBLE (-2400 1375);
FORCEPROP 1 LAST COMMENT_BODY TRUE
J 0
(-2600 1400);
DISPLAY 0.872340 (-2600 1400);
PAINT GREEN (-2600 1400);
DISPLAY INVISIBLE (-2600 1400);
FORCEPROP 2 LAST PATH I9
J 0
(-2675 1575);
DISPLAY 1.021277 (-2675 1575);
DISPLAY INVISIBLE (-2675 1575);
FORCEADD TAP..1
(-250 2800);
FORCEPROP 3 LASTPIN (-300 2800) SIG_NAME M_D_CPU0_SA_DQ<6>
J 0
(-290 2810);
DISPLAY 0.659574 (-290 2810);
PAINT MONO (-290 2810);
DISPLAY INVISIBLE (-290 2810);
FORCEPROP 1 LASTPIN (-300 2800) BN 6
J 0
(-312 2808);
DISPLAY 0.680851 (-312 2808);
PAINT GREEN (-312 2808);
FORCEPROP 2 LAST CDS_LIB standard
J 0
(-250 2800);
PAINT MONO (-250 2800);
DISPLAY INVISIBLE (-250 2800);
FORCEPROP 1 LAST BODY_TYPE PLUMBING
J 0
(-250 2850);
DISPLAY 0.872340 (-250 2850);
PAINT GREEN (-250 2850);
DISPLAY INVISIBLE (-250 2850);
FORCEPROP 1 LAST HDL_TAP TRUE
J 0
(75 2675);
DISPLAY 0.872340 (75 2675);
DISPLAY INVISIBLE (75 2675);
FORCEPROP 1 LAST PATH I90
J 0
(-252 2800);
DISPLAY 0.872340 (-252 2800);
PAINT GREEN (-252 2800);
DISPLAY INVISIBLE (-252 2800);
FORCEADD TAP..1
(-250 2850);
FORCEPROP 3 LASTPIN (-300 2850) SIG_NAME M_D_CPU0_SA_DQ<7>
J 0
(-290 2860);
DISPLAY 0.659574 (-290 2860);
PAINT MONO (-290 2860);
DISPLAY INVISIBLE (-290 2860);
FORCEPROP 1 LASTPIN (-300 2850) BN 7
J 0
(-312 2858);
DISPLAY 0.680851 (-312 2858);
PAINT GREEN (-312 2858);
FORCEPROP 2 LAST CDS_LIB standard
J 0
(-250 2850);
PAINT MONO (-250 2850);
DISPLAY INVISIBLE (-250 2850);
FORCEPROP 1 LAST BODY_TYPE PLUMBING
J 0
(-250 2900);
DISPLAY 0.872340 (-250 2900);
PAINT GREEN (-250 2900);
DISPLAY INVISIBLE (-250 2900);
FORCEPROP 1 LAST HDL_TAP TRUE
J 0
(75 2725);
DISPLAY 0.872340 (75 2725);
DISPLAY INVISIBLE (75 2725);
FORCEPROP 1 LAST PATH I91
J 0
(-252 2850);
DISPLAY 0.872340 (-252 2850);
PAINT GREEN (-252 2850);
DISPLAY INVISIBLE (-252 2850);
FORCEADD TAP..1
(-250 2900);
FORCEPROP 3 LASTPIN (-300 2900) SIG_NAME M_D_CPU0_SA_DQ<8>
J 0
(-290 2910);
DISPLAY 0.659574 (-290 2910);
PAINT MONO (-290 2910);
DISPLAY INVISIBLE (-290 2910);
FORCEPROP 1 LASTPIN (-300 2900) BN 8
J 0
(-312 2908);
DISPLAY 0.680851 (-312 2908);
PAINT GREEN (-312 2908);
FORCEPROP 2 LAST CDS_LIB standard
J 0
(-250 2900);
PAINT MONO (-250 2900);
DISPLAY INVISIBLE (-250 2900);
FORCEPROP 1 LAST BODY_TYPE PLUMBING
J 0
(-250 2950);
DISPLAY 0.872340 (-250 2950);
PAINT GREEN (-250 2950);
DISPLAY INVISIBLE (-250 2950);
FORCEPROP 1 LAST HDL_TAP TRUE
J 0
(75 2775);
DISPLAY 0.872340 (75 2775);
DISPLAY INVISIBLE (75 2775);
FORCEPROP 1 LAST PATH I92
J 0
(-252 2900);
DISPLAY 0.872340 (-252 2900);
PAINT GREEN (-252 2900);
DISPLAY INVISIBLE (-252 2900);
FORCEADD TAP..1
(-250 2950);
FORCEPROP 3 LASTPIN (-300 2950) SIG_NAME M_D_CPU0_SA_DQ<9>
J 0
(-290 2960);
DISPLAY 0.659574 (-290 2960);
PAINT MONO (-290 2960);
DISPLAY INVISIBLE (-290 2960);
FORCEPROP 1 LASTPIN (-300 2950) BN 9
J 0
(-312 2958);
DISPLAY 0.680851 (-312 2958);
PAINT GREEN (-312 2958);
FORCEPROP 2 LAST CDS_LIB standard
J 0
(-250 2950);
PAINT MONO (-250 2950);
DISPLAY INVISIBLE (-250 2950);
FORCEPROP 1 LAST BODY_TYPE PLUMBING
J 0
(-250 3000);
DISPLAY 0.872340 (-250 3000);
PAINT GREEN (-250 3000);
DISPLAY INVISIBLE (-250 3000);
FORCEPROP 1 LAST HDL_TAP TRUE
J 0
(75 2825);
DISPLAY 0.872340 (75 2825);
DISPLAY INVISIBLE (75 2825);
FORCEPROP 1 LAST PATH I93
J 0
(-252 2950);
DISPLAY 0.872340 (-252 2950);
PAINT GREEN (-252 2950);
DISPLAY INVISIBLE (-252 2950);
FORCEADD TAP..1
(-250 3000);
FORCEPROP 3 LASTPIN (-300 3000) SIG_NAME M_D_CPU0_SA_DQ<10>
J 0
(-290 3010);
DISPLAY 0.659574 (-290 3010);
PAINT MONO (-290 3010);
DISPLAY INVISIBLE (-290 3010);
FORCEPROP 1 LASTPIN (-300 3000) BN 10
J 0
(-312 3008);
DISPLAY 0.680851 (-312 3008);
PAINT GREEN (-312 3008);
FORCEPROP 2 LAST CDS_LIB standard
J 0
(-250 3000);
PAINT MONO (-250 3000);
DISPLAY INVISIBLE (-250 3000);
FORCEPROP 1 LAST BODY_TYPE PLUMBING
J 0
(-250 3050);
DISPLAY 0.872340 (-250 3050);
PAINT GREEN (-250 3050);
DISPLAY INVISIBLE (-250 3050);
FORCEPROP 1 LAST HDL_TAP TRUE
J 0
(75 2875);
DISPLAY 0.872340 (75 2875);
DISPLAY INVISIBLE (75 2875);
FORCEPROP 1 LAST PATH I94
J 0
(-252 3000);
DISPLAY 0.872340 (-252 3000);
PAINT GREEN (-252 3000);
DISPLAY INVISIBLE (-252 3000);
FORCEADD TAP..1
(-250 3050);
FORCEPROP 3 LASTPIN (-300 3050) SIG_NAME M_D_CPU0_SA_DQ<11>
J 0
(-290 3060);
DISPLAY 0.659574 (-290 3060);
PAINT MONO (-290 3060);
DISPLAY INVISIBLE (-290 3060);
FORCEPROP 1 LASTPIN (-300 3050) BN 11
J 0
(-312 3058);
DISPLAY 0.680851 (-312 3058);
PAINT GREEN (-312 3058);
FORCEPROP 2 LAST CDS_LIB standard
J 0
(-250 3050);
PAINT MONO (-250 3050);
DISPLAY INVISIBLE (-250 3050);
FORCEPROP 1 LAST BODY_TYPE PLUMBING
J 0
(-250 3100);
DISPLAY 0.872340 (-250 3100);
PAINT GREEN (-250 3100);
DISPLAY INVISIBLE (-250 3100);
FORCEPROP 1 LAST HDL_TAP TRUE
J 0
(75 2925);
DISPLAY 0.872340 (75 2925);
DISPLAY INVISIBLE (75 2925);
FORCEPROP 1 LAST PATH I95
J 0
(-252 3050);
DISPLAY 0.872340 (-252 3050);
PAINT GREEN (-252 3050);
DISPLAY INVISIBLE (-252 3050);
FORCEADD TAP..1
(-250 3100);
FORCEPROP 3 LASTPIN (-300 3100) SIG_NAME M_D_CPU0_SA_DQ<12>
J 0
(-290 3110);
DISPLAY 0.659574 (-290 3110);
PAINT MONO (-290 3110);
DISPLAY INVISIBLE (-290 3110);
FORCEPROP 1 LASTPIN (-300 3100) BN 12
J 0
(-312 3108);
DISPLAY 0.680851 (-312 3108);
PAINT GREEN (-312 3108);
FORCEPROP 2 LAST CDS_LIB standard
J 0
(-250 3100);
PAINT MONO (-250 3100);
DISPLAY INVISIBLE (-250 3100);
FORCEPROP 1 LAST BODY_TYPE PLUMBING
J 0
(-250 3150);
DISPLAY 0.872340 (-250 3150);
PAINT GREEN (-250 3150);
DISPLAY INVISIBLE (-250 3150);
FORCEPROP 1 LAST HDL_TAP TRUE
J 0
(75 2975);
DISPLAY 0.872340 (75 2975);
DISPLAY INVISIBLE (75 2975);
FORCEPROP 1 LAST PATH I96
J 0
(-252 3100);
DISPLAY 0.872340 (-252 3100);
PAINT GREEN (-252 3100);
DISPLAY INVISIBLE (-252 3100);
FORCEADD TAP..1
(-250 3200);
FORCEPROP 3 LASTPIN (-300 3200) SIG_NAME M_D_CPU0_SA_DQ<14>
J 0
(-290 3210);
DISPLAY 0.659574 (-290 3210);
PAINT MONO (-290 3210);
DISPLAY INVISIBLE (-290 3210);
FORCEPROP 1 LASTPIN (-300 3200) BN 14
J 0
(-312 3208);
DISPLAY 0.680851 (-312 3208);
PAINT GREEN (-312 3208);
FORCEPROP 2 LAST CDS_LIB standard
J 0
(-250 3200);
PAINT MONO (-250 3200);
DISPLAY INVISIBLE (-250 3200);
FORCEPROP 1 LAST BODY_TYPE PLUMBING
J 0
(-250 3250);
DISPLAY 0.872340 (-250 3250);
PAINT GREEN (-250 3250);
DISPLAY INVISIBLE (-250 3250);
FORCEPROP 1 LAST HDL_TAP TRUE
J 0
(75 3075);
DISPLAY 0.872340 (75 3075);
DISPLAY INVISIBLE (75 3075);
FORCEPROP 1 LAST PATH I97
J 0
(-252 3200);
DISPLAY 0.872340 (-252 3200);
PAINT GREEN (-252 3200);
DISPLAY INVISIBLE (-252 3200);
FORCEADD TAP..1
(-250 3150);
FORCEPROP 3 LASTPIN (-300 3150) SIG_NAME M_D_CPU0_SA_DQ<13>
J 0
(-290 3160);
DISPLAY 0.659574 (-290 3160);
PAINT MONO (-290 3160);
DISPLAY INVISIBLE (-290 3160);
FORCEPROP 1 LASTPIN (-300 3150) BN 13
J 0
(-312 3158);
DISPLAY 0.680851 (-312 3158);
PAINT GREEN (-312 3158);
FORCEPROP 2 LAST CDS_LIB standard
J 0
(-250 3150);
PAINT MONO (-250 3150);
DISPLAY INVISIBLE (-250 3150);
FORCEPROP 1 LAST BODY_TYPE PLUMBING
J 0
(-250 3200);
DISPLAY 0.872340 (-250 3200);
PAINT GREEN (-250 3200);
DISPLAY INVISIBLE (-250 3200);
FORCEPROP 1 LAST HDL_TAP TRUE
J 0
(75 3025);
DISPLAY 0.872340 (75 3025);
DISPLAY INVISIBLE (75 3025);
FORCEPROP 1 LAST PATH I98
J 0
(-252 3150);
DISPLAY 0.872340 (-252 3150);
PAINT GREEN (-252 3150);
DISPLAY INVISIBLE (-252 3150);
FORCEADD TAP..1
(-250 3250);
FORCEPROP 3 LASTPIN (-300 3250) SIG_NAME M_D_CPU0_SA_DQ<15>
J 0
(-290 3260);
DISPLAY 0.659574 (-290 3260);
PAINT MONO (-290 3260);
DISPLAY INVISIBLE (-290 3260);
FORCEPROP 1 LASTPIN (-300 3250) BN 15
J 0
(-312 3258);
DISPLAY 0.680851 (-312 3258);
PAINT GREEN (-312 3258);
FORCEPROP 2 LAST CDS_LIB standard
J 0
(-250 3250);
PAINT MONO (-250 3250);
DISPLAY INVISIBLE (-250 3250);
FORCEPROP 1 LAST BODY_TYPE PLUMBING
J 0
(-250 3300);
DISPLAY 0.872340 (-250 3300);
PAINT GREEN (-250 3300);
DISPLAY INVISIBLE (-250 3300);
FORCEPROP 1 LAST HDL_TAP TRUE
J 0
(75 3125);
DISPLAY 0.872340 (75 3125);
DISPLAY INVISIBLE (75 3125);
FORCEPROP 1 LAST PATH I99
J 0
(-252 3250);
DISPLAY 0.872340 (-252 3250);
PAINT GREEN (-252 3250);
DISPLAY INVISIBLE (-252 3250);
FORCEADD CAD_NOTE..1
(1600 -400);
FORCEPROP 0 LAST S1 PLACE THE BYPASS CAPS CLOSE TO DIMM
J 0
(1475 -525);
DISPLAY 1.021277 (1475 -525);
PAINT WHITE (1475 -525);
FORCEPROP 2 LAST CDS_LIB logical_power
J 0
(1600 -400);
PAINT MONO (1600 -400);
DISPLAY INVISIBLE (1600 -400);
FORCEPROP 1 LAST COMMENT_BODY TRUE
J 0
(1625 -300);
DISPLAY 0.978723 (1625 -300);
DISPLAY INVISIBLE (1625 -300);
FORCEADD QUANTA_TITLE_BLOCK_C..1
(6075 -1700);
FORCEPROP 0 LAST CDS_CON_LAST_MODIFIED Fri Aug 25 14:01:07 2023
J 0
(4190 -1685);
PAINT MONO (4190 -1685);
DISPLAY INVISIBLE (4190 -1685);
FORCEPROP 1 LAST CUSTOM_TXT_CDS <CON_LAST_MODIFIED>
J 0
(4190 -1685);
DISPLAY 0.978723 (4190 -1685);
FORCEPROP 2 LAST CUSTOM_TXT_CDS <XR_PAGE_TITLE>
J 0
(-1815 3550);
DISPLAY 0.638298 (-1815 3550);
PAINT PINK (-1815 3550);
DISPLAY INVISIBLE (-1815 3550);
FORCEPROP 2 LAST CUSTOM_TXT_CDS <Q_NUMBER>
J 0
(4672 -1597);
DISPLAY 1.212766 (4672 -1597);
FORCEPROP 1 LAST CUSTOM_TXT_CDS <NAME_2>
J 0
(2900 -1650);
FORCEPROP 1 LAST CUSTOM_TXT_CDS <NAME_1>
J 0
(2900 -1525);
FORCEPROP 1 LAST CUSTOM_TXT_CDS <Q_PROJ>
J 0
(3693 -1598);
DISPLAY 1.212766 (3693 -1598);
FORCEPROP 1 LAST CUSTOM_TXT_CDS <Q_REV>
J 0
(5891 -1597);
DISPLAY 1.212766 (5891 -1597);
FORCEPROP 1 LAST CUSTOM_TXT_CDS <CON_PAGE_NUM> OF <CON_TOTAL_PAGES>
J 0
(5629 -1682);
DISPLAY 0.978723 (5629 -1682);
FORCEPROP 1 LAST Q_TITLE DDR5 - CPU0 CHD DIMM1(YELLOW)
J 0
(-3291 -1674);
DISPLAY 2.446809 (-3291 -1674);
PAINT GREEN (-3291 -1674);
FORCEPROP 1 LAST Q_DEPT 
J 1
(2312 -1651);
DISPLAY 1.957447 (2312 -1651);
PAINT GREEN (2312 -1651);
FORCEPROP 1 LAST COMMENT_BODY TRUE
J 0
(6087 -1713);
DISPLAY 0.978723 (6087 -1713);
PAINT GREEN (6087 -1713);
DISPLAY INVISIBLE (6087 -1713);
FORCEPROP 2 LAST CDS_XR_PAGE_TITLE CR-88 : @S9S_MB_2U_LIB.S9S_MB_2U(SCH_1):PAGE88
J 0
(-1815 3550);
DISPLAY 0.638298 (-1815 3550);
PAINT PINK (-1815 3550);
DISPLAY INVISIBLE (-1815 3550);
FORCEPROP 2 LAST CDS_LIB pure_quanta
J 0
(6075 -1700);
PAINT MONO (6075 -1700);
DISPLAY INVISIBLE (6075 -1700);
FORCEPROP 1 LAST CDS_LMAN_SYM_OUTLINE -9475,6775,100,-125
J 0
(6075 -1700);
DISPLAY 0.468085 (6075 -1700);
PAINT GREEN (6075 -1700);
DISPLAY INVISIBLE (6075 -1700);
FORCEPROP 2 LAST PAGE_BORDER TRUE
J 0
(-1815 3550);
DISPLAY 0.638298 (-1815 3550);
PAINT PINK (-1815 3550);
DISPLAY INVISIBLE (-1815 3550);
WIRE 17 -1 (-200 4025)(-200 4075);
WIRE 17 -1 (-200 3975)(-200 4025);
WIRE 17 -1 (-200 4075)(525 4075);
FORCEPROP 2 LAST SIG_NAME M_D_CPU0_SA_DQ<31:0>
J 0
(-135 4085);
DISPLAY 0.680851 (-135 4085);
PAINT WHITE (-135 4085);
WIRE 17 -1 (-1950 2625)(-1950 2675);
WIRE 17 -1 (-1950 2575)(-1950 2625);
WIRE 17 -1 (-2775 2675)(-1950 2675);
FORCEPROP 2 LAST SIG_NAME M_D_CPU0_SA_CB<7:0>
J 0
(-2685 2685);
DISPLAY 0.680851 (-2685 2685);
PAINT WHITE (-2685 2685);
WIRE 17 -1 (-1950 2525)(-1950 2575);
WIRE 17 -1 (-1950 2475)(-1950 2525);
WIRE 17 -1 (-1950 2425)(-1950 2475);
WIRE 17 -1 (-1950 2375)(-1950 2425);
WIRE 17 -1 (-1950 2325)(-1950 2375);
WIRE 17 -1 (-1950 2175)(-1950 2225);
WIRE 17 -1 (-1950 2125)(-1950 2175);
WIRE 17 -1 (-2775 2225)(-1950 2225);
FORCEPROP 2 LAST SIG_NAME M_D_CPU0_SB_CB<7:0>
J 0
(-2685 2235);
DISPLAY 0.680851 (-2685 2235);
PAINT WHITE (-2685 2235);
WIRE 17 -1 (-1950 3375)(-1950 3425);
WIRE 17 -1 (-1950 3425)(-1950 3475);
WIRE 17 -1 (-1950 3475)(-1950 3525);
WIRE 17 -1 (-1950 3525)(-1950 3575);
WIRE 17 -1 (-1950 3575)(-1950 3625);
WIRE 17 -1 (-1950 3625)(-1950 3675);
WIRE 17 -1 (-2775 3675)(-1950 3675);
FORCEPROP 2 LAST SIG_NAME M_D_CPU0_SB_CA<6:0>
J 0
(-2685 3685);
DISPLAY 0.680851 (-2685 3685);
PAINT WHITE (-2685 3685);
WIRE 17 -1 (-1950 3825)(-1950 3875);
WIRE 17 -1 (-1950 3775)(-1950 3825);
WIRE 17 -1 (-1950 3875)(-1950 3925);
WIRE 17 -1 (-1950 3925)(-1950 3975);
WIRE 17 -1 (-1950 3975)(-1950 4025);
WIRE 17 -1 (-1950 4025)(-1950 4075);
WIRE 17 -1 (-2775 4075)(-1950 4075);
FORCEPROP 2 LAST SIG_NAME M_D_CPU0_SA_CA<6:0>
J 0
(-2685 4085);
DISPLAY 0.680851 (-2685 4085);
PAINT WHITE (-2685 4085);
WIRE 17 -1 (-1950 2075)(-1950 2125);
WIRE 17 -1 (-1950 2025)(-1950 2075);
WIRE 17 -1 (-1950 1975)(-1950 2025);
WIRE 17 -1 (-1950 1925)(-1950 1975);
WIRE 17 -1 (-1950 1875)(-1950 1925);
WIRE 17 -1 (-200 3875)(-200 3925);
WIRE 17 -1 (-200 3825)(-200 3875);
WIRE 17 -1 (-200 3925)(-200 3975);
WIRE 17 -1 (-200 3775)(-200 3825);
WIRE 17 -1 (-200 3725)(-200 3775);
WIRE 17 -1 (-200 3675)(-200 3725);
WIRE 17 -1 (-200 3625)(-200 3675);
WIRE 17 -1 (-200 3575)(-200 3625);
WIRE 17 -1 (-200 3525)(-200 3575);
WIRE 17 -1 (-200 3475)(-200 3525);
WIRE 17 -1 (-200 3425)(-200 3475);
WIRE 17 -1 (-200 3375)(-200 3425);
WIRE 17 -1 (-200 3325)(-200 3375);
WIRE 17 -1 (-200 3275)(-200 3325);
WIRE 17 -1 (-200 3225)(-200 3275);
WIRE 17 -1 (-200 3175)(-200 3225);
WIRE 17 -1 (-200 3125)(-200 3175);
WIRE 17 -1 (-200 3075)(-200 3125);
WIRE 17 -1 (-200 3025)(-200 3075);
WIRE 17 -1 (-200 2975)(-200 3025);
WIRE 17 -1 (-200 2925)(-200 2975);
WIRE 17 -1 (-200 2875)(-200 2925);
WIRE 17 -1 (-200 2825)(-200 2875);
WIRE 17 -1 (-200 2775)(-200 2825);
WIRE 17 -1 (-200 2725)(-200 2775);
WIRE 17 -1 (-200 2675)(-200 2725);
WIRE 17 -1 (-200 2625)(-200 2675);
WIRE 17 -1 (-200 2575)(-200 2625);
WIRE 17 -1 (-200 2525)(-200 2575);
WIRE 17 -1 (-200 2375)(-200 2425);
WIRE 17 -1 (-200 2325)(-200 2375);
WIRE 17 -1 (-200 2425)(525 2425);
FORCEPROP 2 LAST SIG_NAME M_D_CPU0_SB_DQ<31:0>
J 0
(-135 2435);
DISPLAY 0.680851 (-135 2435);
PAINT WHITE (-135 2435);
WIRE 17 -1 (-200 2275)(-200 2325);
WIRE 17 -1 (-200 2225)(-200 2275);
WIRE 17 -1 (-200 2175)(-200 2225);
WIRE 17 -1 (-200 2125)(-200 2175);
WIRE 17 -1 (-200 2075)(-200 2125);
WIRE 17 -1 (-200 2025)(-200 2075);
WIRE 17 -1 (-200 1975)(-200 2025);
WIRE 17 -1 (-200 1925)(-200 1975);
WIRE 17 -1 (-200 1875)(-200 1925);
WIRE 17 -1 (-200 1825)(-200 1875);
WIRE 17 -1 (-200 1775)(-200 1825);
WIRE 17 -1 (-200 1725)(-200 1775);
WIRE 17 -1 (-200 1675)(-200 1725);
WIRE 17 -1 (-200 1625)(-200 1675);
WIRE 17 -1 (-200 1575)(-200 1625);
WIRE 17 -1 (-200 1525)(-200 1575);
WIRE 17 -1 (-200 1475)(-200 1525);
WIRE 17 -1 (-200 1425)(-200 1475);
WIRE 17 -1 (-200 1375)(-200 1425);
WIRE 17 -1 (-200 1325)(-200 1375);
WIRE 17 -1 (-200 1275)(-200 1325);
WIRE 17 -1 (-200 1225)(-200 1275);
WIRE 17 -1 (-200 1175)(-200 1225);
WIRE 17 -1 (-200 1125)(-200 1175);
WIRE 17 -1 (-200 1075)(-200 1125);
WIRE 17 -1 (-200 1025)(-200 1075);
WIRE 17 -1 (-200 975)(-200 1025);
WIRE 17 -1 (-200 925)(-200 975);
WIRE 17 -1 (-200 875)(-200 925);
WIRE 17 -1 (2550 2125)(2550 2225);
WIRE 17 -1 (2550 2225)(2550 2325);
WIRE 17 -1 (2550 2325)(2550 2425);
WIRE 17 -1 (2550 2525)(2550 2425);
WIRE 17 -1 (2550 2525)(2550 2625);
WIRE 17 -1 (2550 2625)(2550 2725);
WIRE 17 -1 (2550 2725)(2550 2825);
WIRE 17 -1 (2550 2825)(2550 2925);
WIRE 17 -1 (2550 2925)(2550 3025);
WIRE 17 -1 (2550 3025)(3575 3025);
FORCEPROP 2 LAST SIG_NAME M_D_CPU0_SB_DQS_DP<9:0>
J 0
(2790 3035);
DISPLAY 0.680851 (2790 3035);
PAINT WHITE (2790 3035);
WIRE 17 -1 (2550 3175)(2550 3275);
WIRE 17 -1 (2550 3275)(2550 3375);
WIRE 17 -1 (2550 3375)(2550 3475);
WIRE 17 -1 (2550 3575)(2550 3475);
WIRE 17 -1 (2550 3575)(2550 3675);
WIRE 17 -1 (2550 3675)(2550 3775);
WIRE 17 -1 (2550 3775)(2550 3875);
WIRE 17 -1 (2550 3875)(2550 3975);
WIRE 17 -1 (2550 3975)(2550 4075);
WIRE 17 -1 (2550 4075)(3575 4075);
FORCEPROP 2 LAST SIG_NAME M_D_CPU0_SA_DQS_DP<9:0>
J 0
(2790 4085);
DISPLAY 0.680851 (2790 4085);
PAINT WHITE (2790 4085);
WIRE 17 -1 (2725 2075)(2725 2175);
WIRE 17 -1 (2725 2175)(2725 2275);
WIRE 17 -1 (2725 2275)(2725 2375);
WIRE 17 -1 (2725 2475)(2725 2375);
WIRE 17 -1 (2725 2475)(2725 2575);
WIRE 17 -1 (2725 2575)(2725 2675);
WIRE 17 -1 (2725 2675)(2725 2775);
WIRE 17 -1 (2725 2775)(2725 2875);
WIRE 17 -1 (2725 2875)(2725 2975);
WIRE 17 -1 (2725 2975)(3575 2975);
FORCEPROP 2 LAST SIG_NAME M_D_CPU0_SB_DQS_DN<9:0>
J 0
(2790 2985);
DISPLAY 0.680851 (2790 2985);
PAINT WHITE (2790 2985);
WIRE 17 -1 (2725 3125)(2725 3225);
WIRE 17 -1 (2725 3225)(2725 3325);
WIRE 17 -1 (2725 3325)(2725 3425);
WIRE 17 -1 (2725 3525)(2725 3425);
WIRE 17 -1 (2725 3525)(2725 3625);
WIRE 17 -1 (2725 3625)(2725 3725);
WIRE 17 -1 (2725 3725)(2725 3825);
WIRE 17 -1 (2725 3825)(2725 3925);
WIRE 17 -1 (2725 3925)(2725 4025);
WIRE 17 -1 (2725 4025)(3575 4025);
FORCEPROP 2 LAST SIG_NAME M_D_CPU0_SA_DQS_DN<9:0>
J 0
(2790 4035);
DISPLAY 0.680851 (2790 4035);
PAINT WHITE (2790 4035);
WIRE 16 -1 (-2725 1875)(-2725 1600);
WIRE 16 -1 (4175 4550)(4175 4050);
WIRE 16 -1 (1475 275)(1475 450);
WIRE 16 -1 (2475 450)(2475 400);
WIRE 16 -1 (-1675 -275)(-1675 -200);
WIRE 16 -1 (1475 75)(1475 -150);
WIRE 16 -1 (3100 -150)(3100 -75);
WIRE 16 -1 (4175 400)(4175 800);
WIRE 16 -1 (5875 700)(5875 400);
WIRE 16 -1 (5875 750)(5875 700);
WIRE 16 -1 (5625 700)(5875 700);
WIRE 16 3135 (1125 675)(1125 -625);
WIRE 16 3135 (3725 675)(1125 675);
WIRE 16 3135 (1125 -625)(3725 -625);
WIRE 16 3135 (3725 -625)(3725 675);
WIRE 16 -1 (-1600 1275)(-1650 1275);
WIRE 16 -1 (-2875 1325)(-1600 1325);
FORCEPROP 2 LAST SIG_NAME I3C_SPD_DDRABCD_CPU0_LVC1_SCL
J 0
(-2760 1335);
DISPLAY 0.680851 (-2760 1335);
PAINT WHITE (-2760 1335);
WIRE 16 -1 (-1600 1325)(-1600 1275);
WIRE 16 -1 (-2725 1600)(-1675 1600);
WIRE 16 -1 (-1675 1700)(-2775 1700);
FORCEPROP 2 LAST SIG_NAME M_D_CPU0_ALERT_N
J 0
(-2687 1709);
DISPLAY 0.680851 (-2687 1709);
PAINT WHITE (-2687 1709);
WIRE 16 -1 (-1675 1500)(-2675 1500);
FORCEPROP 2 LAST SIG_NAME I3C_SPD_DDRABCD_CPU0_LVC1_SDA
J 0
(-2685 1510);
DISPLAY 0.680851 (-2685 1510);
PAINT WHITE (-2685 1510);
WIRE 16 -1 (-1675 1550)(-2675 1550);
FORCEPROP 2 LAST SIG_NAME PD_CHD_CPU0_DIMM1_SAA
J 0
(-2685 1560);
DISPLAY 0.680851 (-2685 1560);
PAINT WHITE (-2685 1560);
WIRE 16 -1 (-2050 1800)(-2775 1800);
FORCEPROP 2 LAST SIG_NAME RST_M_CD_CPU0_FPGA_N
J 0
(-2687 1809);
DISPLAY 0.680851 (-2687 1809);
PAINT WHITE (-2687 1809);
WIRE 16 -1 (-2050 1800)(-2050 1750);
WIRE 16 -1 (-2050 1750)(-1675 1750);
WIRE 16 -1 (-1850 1850)(-1675 1850);
WIRE 16 -1 (-3200 1325)(-3075 1325);
WIRE 16 -1 (-3200 1450)(-3200 1325);
WIRE 16 -1 (-3200 1450)(-1675 1450);
FORCEPROP 2 LAST SIG_NAME I3C_SPD_DDRABCD_CPU0_LVC1_SCL_R7
J 0
(-2735 1460);
DISPLAY 0.680851 (-2735 1460);
PAINT WHITE (-2735 1460);
WIRE 16 -1 (-1675 1200)(-2775 1200);
FORCEPROP 2 LAST SIG_NAME PWRGD_CHD_CPU0_DIMM1
J 0
(-2687 1209);
DISPLAY 0.680851 (-2687 1209);
PAINT WHITE (-2687 1209);
WIRE 16 -1 (2350 4000)(2625 4000);
WIRE 16 -1 (2350 3900)(2625 3900);
WIRE 16 -1 (2350 3800)(2625 3800);
WIRE 16 -1 (2350 3700)(2625 3700);
WIRE 16 -1 (2350 3600)(2625 3600);
WIRE 16 -1 (2350 3500)(2625 3500);
WIRE 16 -1 (2350 3400)(2625 3400);
WIRE 16 -1 (2350 3300)(2625 3300);
WIRE 16 -1 (2350 3200)(2625 3200);
WIRE 16 -1 (2350 3100)(2625 3100);
WIRE 16 -1 (2350 2950)(2625 2950);
WIRE 16 -1 (2350 2850)(2625 2850);
WIRE 16 -1 (2350 2750)(2625 2750);
WIRE 16 -1 (2350 2650)(2625 2650);
WIRE 16 -1 (2350 2550)(2625 2550);
WIRE 16 -1 (2350 2450)(2625 2450);
WIRE 16 -1 (2350 2350)(2625 2350);
WIRE 16 -1 (2350 2250)(2625 2250);
WIRE 16 -1 (2350 2150)(2625 2150);
WIRE 16 -1 (2350 2050)(2625 2050);
WIRE 16 -1 (2350 4050)(2450 4050);
WIRE 16 -1 (2350 3950)(2450 3950);
WIRE 16 -1 (2350 3850)(2450 3850);
WIRE 16 -1 (2350 3750)(2450 3750);
WIRE 16 -1 (2350 3650)(2450 3650);
WIRE 16 -1 (2350 3550)(2450 3550);
WIRE 16 -1 (2350 3450)(2450 3450);
WIRE 16 -1 (2350 3350)(2450 3350);
WIRE 16 -1 (2350 3250)(2450 3250);
WIRE 16 -1 (2350 3150)(2450 3150);
WIRE 16 -1 (2350 3000)(2450 3000);
WIRE 16 -1 (2350 2900)(2450 2900);
WIRE 16 -1 (2350 2800)(2450 2800);
WIRE 16 -1 (2350 2700)(2450 2700);
WIRE 16 -1 (2350 2600)(2450 2600);
WIRE 16 -1 (2350 2500)(2450 2500);
WIRE 16 -1 (2350 2400)(2450 2400);
WIRE 16 -1 (2350 2300)(2450 2300);
WIRE 16 -1 (2350 2200)(2450 2200);
WIRE 16 -1 (2350 2100)(2450 2100);
WIRE 16 -1 (-475 3950)(-300 3950);
WIRE 16 -1 (-475 4000)(-300 4000);
WIRE 16 -1 (-475 3900)(-300 3900);
WIRE 16 -1 (-475 3800)(-300 3800);
WIRE 16 -1 (4425 3950)(4175 3950);
WIRE 16 -1 (4175 4000)(4175 3950);
WIRE 16 -1 (4175 4000)(4425 4000);
WIRE 16 -1 (4175 4050)(4175 4000);
WIRE 16 -1 (4425 4050)(4175 4050);
WIRE 16 -1 (2475 -75)(2475 75);
WIRE 16 -1 (3100 -75)(2475 -75);
WIRE 16 -1 (3100 -75)(3100 75);
WIRE 16 -1 (2475 400)(2475 275);
WIRE 16 -1 (3100 400)(2475 400);
WIRE 16 -1 (3100 275)(3100 400);
WIRE 16 -1 (4425 3900)(4175 3900);
WIRE 16 -1 (4175 3850)(4175 3900);
WIRE 16 -1 (4175 3850)(4425 3850);
WIRE 16 -1 (4175 3800)(4175 3850);
WIRE 16 -1 (4425 3800)(4175 3800);
WIRE 16 -1 (4175 3750)(4175 3800);
WIRE 16 -1 (4175 3750)(4425 3750);
WIRE 16 -1 (4175 3700)(4175 3750);
WIRE 16 -1 (4175 3700)(4425 3700);
WIRE 16 -1 (4175 3650)(4175 3700);
WIRE 16 -1 (4175 3650)(4425 3650);
WIRE 16 -1 (4175 3600)(4175 3650);
WIRE 16 -1 (4175 3600)(4425 3600);
WIRE 16 -1 (4175 3550)(4425 3550);
WIRE 16 -1 (4175 3550)(4175 3600);
WIRE 16 -1 (4175 3500)(4175 3550);
WIRE 16 -1 (4175 3500)(4425 3500);
WIRE 16 -1 (4175 3450)(4175 3500);
WIRE 16 -1 (4175 3450)(4425 3450);
WIRE 16 -1 (4175 3400)(4175 3450);
WIRE 16 -1 (4175 3400)(4425 3400);
WIRE 16 -1 (4175 3350)(4175 3400);
WIRE 16 -1 (4175 3350)(4425 3350);
WIRE 16 -1 (4175 3300)(4175 3350);
WIRE 16 -1 (4425 3300)(4175 3300);
WIRE 16 -1 (4175 3250)(4175 3300);
WIRE 16 -1 (4175 3250)(4425 3250);
WIRE 16 -1 (4175 3200)(4175 3250);
WIRE 16 -1 (4175 3200)(4425 3200);
WIRE 16 -1 (4175 3150)(4175 3200);
WIRE 16 -1 (4175 3150)(4425 3150);
WIRE 16 -1 (4175 3100)(4175 3150);
WIRE 16 -1 (4175 3100)(4425 3100);
WIRE 16 -1 (4175 3050)(4425 3050);
WIRE 16 -1 (4175 3050)(4175 3100);
WIRE 16 -1 (4175 3000)(4175 3050);
WIRE 16 -1 (4175 3000)(4425 3000);
WIRE 16 -1 (4175 2950)(4175 3000);
WIRE 16 -1 (4175 2950)(4425 2950);
WIRE 16 -1 (4175 2900)(4175 2950);
WIRE 16 -1 (4175 2900)(4425 2900);
WIRE 16 -1 (4175 2850)(4175 2900);
WIRE 16 -1 (4175 2850)(4425 2850);
WIRE 16 -1 (4175 2800)(4175 2850);
WIRE 16 -1 (4425 2800)(4175 2800);
WIRE 16 -1 (4175 2750)(4175 2800);
WIRE 16 -1 (4175 2750)(4425 2750);
WIRE 16 -1 (4175 2700)(4175 2750);
WIRE 16 -1 (4175 2700)(4425 2700);
WIRE 16 -1 (4175 2650)(4175 2700);
WIRE 16 -1 (4175 2650)(4425 2650);
WIRE 16 -1 (4175 2600)(4175 2650);
WIRE 16 -1 (4175 2600)(4425 2600);
WIRE 16 -1 (4175 2550)(4425 2550);
WIRE 16 -1 (4175 2550)(4175 2600);
WIRE 16 -1 (4175 2500)(4175 2550);
WIRE 16 -1 (4175 2500)(4425 2500);
WIRE 16 -1 (4175 2450)(4175 2500);
WIRE 16 -1 (4175 2450)(4425 2450);
WIRE 16 -1 (4175 2400)(4175 2450);
WIRE 16 -1 (4175 2400)(4425 2400);
WIRE 16 -1 (4175 2350)(4175 2400);
WIRE 16 -1 (4175 2350)(4425 2350);
WIRE 16 -1 (4175 2300)(4175 2350);
WIRE 16 -1 (4425 2300)(4175 2300);
WIRE 16 -1 (4175 2250)(4175 2300);
WIRE 16 -1 (4175 2250)(4425 2250);
WIRE 16 -1 (4175 2200)(4175 2250);
WIRE 16 -1 (4175 2200)(4425 2200);
WIRE 16 -1 (4175 2150)(4175 2200);
WIRE 16 -1 (4175 2150)(4425 2150);
WIRE 16 -1 (4175 2100)(4175 2150);
WIRE 16 -1 (4175 2100)(4425 2100);
WIRE 16 -1 (4175 2050)(4175 2100);
WIRE 16 -1 (4175 2050)(4425 2050);
WIRE 16 -1 (4175 2000)(4425 2000);
WIRE 16 -1 (4175 2000)(4175 2050);
WIRE 16 -1 (4175 1950)(4175 2000);
WIRE 16 -1 (4175 1950)(4425 1950);
WIRE 16 -1 (4175 1900)(4175 1950);
WIRE 16 -1 (4175 1900)(4425 1900);
WIRE 16 -1 (4175 1850)(4175 1900);
WIRE 16 -1 (4175 1850)(4425 1850);
WIRE 16 -1 (4175 1800)(4175 1850);
WIRE 16 -1 (4425 1800)(4175 1800);
WIRE 16 -1 (4175 1750)(4175 1800);
WIRE 16 -1 (4175 1750)(4425 1750);
WIRE 16 -1 (4175 1700)(4175 1750);
WIRE 16 -1 (4175 1700)(4425 1700);
WIRE 16 -1 (4175 1650)(4175 1700);
WIRE 16 -1 (4175 1650)(4425 1650);
WIRE 16 -1 (4175 1600)(4175 1650);
WIRE 16 -1 (4175 1600)(4425 1600);
WIRE 16 -1 (4175 1550)(4175 1600);
WIRE 16 -1 (4175 1550)(4425 1550);
WIRE 16 -1 (4175 1500)(4425 1500);
WIRE 16 -1 (4175 1500)(4175 1550);
WIRE 16 -1 (4175 1450)(4175 1500);
WIRE 16 -1 (4175 1450)(4425 1450);
WIRE 16 -1 (4175 1400)(4175 1450);
WIRE 16 -1 (4175 1400)(4425 1400);
WIRE 16 -1 (4175 1350)(4175 1400);
WIRE 16 -1 (4175 1350)(4425 1350);
WIRE 16 -1 (4175 1300)(4175 1350);
WIRE 16 -1 (4425 1300)(4175 1300);
WIRE 16 -1 (4175 1250)(4175 1300);
WIRE 16 -1 (4175 1250)(4425 1250);
WIRE 16 -1 (4175 1200)(4175 1250);
WIRE 16 -1 (4175 1200)(4425 1200);
WIRE 16 -1 (4175 1150)(4175 1200);
WIRE 16 -1 (4175 1150)(4425 1150);
WIRE 16 -1 (4175 1100)(4175 1150);
WIRE 16 -1 (4175 1100)(4425 1100);
WIRE 16 -1 (4175 1050)(4175 1100);
WIRE 16 -1 (4175 1050)(4425 1050);
WIRE 16 -1 (4175 1000)(4425 1000);
WIRE 16 -1 (4175 1000)(4175 1050);
WIRE 16 -1 (4175 950)(4175 1000);
WIRE 16 -1 (4175 950)(4425 950);
WIRE 16 -1 (4175 900)(4175 950);
WIRE 16 -1 (4175 900)(4425 900);
WIRE 16 -1 (4175 850)(4175 900);
WIRE 16 -1 (4175 850)(4425 850);
WIRE 16 -1 (4175 800)(4175 850);
WIRE 16 -1 (4175 800)(4425 800);
WIRE 16 -1 (5625 4050)(5875 4050);
WIRE 16 -1 (5625 4000)(5875 4000);
WIRE 16 -1 (5875 4050)(5875 4000);
WIRE 16 -1 (5625 3950)(5875 3950);
WIRE 16 -1 (5875 4000)(5875 3950);
WIRE 16 -1 (5625 3900)(5875 3900);
WIRE 16 -1 (5875 3950)(5875 3900);
WIRE 16 -1 (5625 3850)(5875 3850);
WIRE 16 -1 (5875 3900)(5875 3850);
WIRE 16 -1 (5625 3800)(5875 3800);
WIRE 16 -1 (5875 3850)(5875 3800);
WIRE 16 -1 (5625 3750)(5875 3750);
WIRE 16 -1 (5875 3800)(5875 3750);
WIRE 16 -1 (5625 3700)(5875 3700);
WIRE 16 -1 (5875 3750)(5875 3700);
WIRE 16 -1 (5625 3650)(5875 3650);
WIRE 16 -1 (5875 3700)(5875 3650);
WIRE 16 -1 (5625 3600)(5875 3600);
WIRE 16 -1 (5875 3650)(5875 3600);
WIRE 16 -1 (5625 3550)(5875 3550);
WIRE 16 -1 (5875 3600)(5875 3550);
WIRE 16 -1 (5625 3500)(5875 3500);
WIRE 16 -1 (5875 3550)(5875 3500);
WIRE 16 -1 (5625 3450)(5875 3450);
WIRE 16 -1 (5875 3500)(5875 3450);
WIRE 16 -1 (5625 3400)(5875 3400);
WIRE 16 -1 (5875 3450)(5875 3400);
WIRE 16 -1 (5625 3350)(5875 3350);
WIRE 16 -1 (5875 3400)(5875 3350);
WIRE 16 -1 (5625 3300)(5875 3300);
WIRE 16 -1 (5875 3300)(5875 3350);
WIRE 16 -1 (5625 3250)(5875 3250);
WIRE 16 -1 (5875 3300)(5875 3250);
WIRE 16 -1 (5875 3200)(5625 3200);
WIRE 16 -1 (5875 3250)(5875 3200);
WIRE 16 -1 (5875 3150)(5625 3150);
WIRE 16 -1 (5875 3200)(5875 3150);
WIRE 16 -1 (5625 3100)(5875 3100);
WIRE 16 -1 (5875 3150)(5875 3100);
WIRE 16 -1 (5625 3050)(5875 3050);
WIRE 16 -1 (5875 3100)(5875 3050);
WIRE 16 -1 (5625 3000)(5875 3000);
WIRE 16 -1 (5875 3050)(5875 3000);
WIRE 16 -1 (5625 2950)(5875 2950);
WIRE 16 -1 (5875 3000)(5875 2950);
WIRE 16 -1 (5625 2900)(5875 2900);
WIRE 16 -1 (5875 2950)(5875 2900);
WIRE 16 -1 (5625 2850)(5875 2850);
WIRE 16 -1 (5875 2900)(5875 2850);
WIRE 16 -1 (5625 2800)(5875 2800);
WIRE 16 -1 (5875 2800)(5875 2850);
WIRE 16 -1 (5625 2750)(5875 2750);
WIRE 16 -1 (5875 2800)(5875 2750);
WIRE 16 -1 (5875 2700)(5625 2700);
WIRE 16 -1 (5875 2750)(5875 2700);
WIRE 16 -1 (5875 2650)(5625 2650);
WIRE 16 -1 (5875 2700)(5875 2650);
WIRE 16 -1 (5625 2600)(5875 2600);
WIRE 16 -1 (5875 2650)(5875 2600);
WIRE 16 -1 (5625 2550)(5875 2550);
WIRE 16 -1 (5875 2600)(5875 2550);
WIRE 16 -1 (5625 2500)(5875 2500);
WIRE 16 -1 (5875 2550)(5875 2500);
WIRE 16 -1 (5625 2450)(5875 2450);
WIRE 16 -1 (5875 2500)(5875 2450);
WIRE 16 -1 (5625 2400)(5875 2400);
WIRE 16 -1 (5875 2450)(5875 2400);
WIRE 16 -1 (5625 2350)(5875 2350);
WIRE 16 -1 (5875 2400)(5875 2350);
WIRE 16 -1 (5625 2300)(5875 2300);
WIRE 16 -1 (5875 2300)(5875 2350);
WIRE 16 -1 (5625 2250)(5875 2250);
WIRE 16 -1 (5875 2300)(5875 2250);
WIRE 16 -1 (5875 2200)(5625 2200);
WIRE 16 -1 (5875 2250)(5875 2200);
WIRE 16 -1 (5875 2150)(5625 2150);
WIRE 16 -1 (5875 2200)(5875 2150);
WIRE 16 -1 (5625 2100)(5875 2100);
WIRE 16 -1 (5875 2150)(5875 2100);
WIRE 16 -1 (5625 2050)(5875 2050);
WIRE 16 -1 (5875 2100)(5875 2050);
WIRE 16 -1 (5625 2000)(5875 2000);
WIRE 16 -1 (5875 2050)(5875 2000);
WIRE 16 -1 (5625 1950)(5875 1950);
WIRE 16 -1 (5875 2000)(5875 1950);
WIRE 16 -1 (5625 1900)(5875 1900);
WIRE 16 -1 (5875 1950)(5875 1900);
WIRE 16 -1 (5625 1850)(5875 1850);
WIRE 16 -1 (5875 1900)(5875 1850);
WIRE 16 -1 (5625 1800)(5875 1800);
WIRE 16 -1 (5875 1800)(5875 1850);
WIRE 16 -1 (5625 1750)(5875 1750);
WIRE 16 -1 (5875 1800)(5875 1750);
WIRE 16 -1 (5875 1700)(5625 1700);
WIRE 16 -1 (5875 1750)(5875 1700);
WIRE 16 -1 (5875 1650)(5625 1650);
WIRE 16 -1 (5875 1700)(5875 1650);
WIRE 16 -1 (5875 1600)(5625 1600);
WIRE 16 -1 (5875 1650)(5875 1600);
WIRE 16 -1 (5875 1550)(5625 1550);
WIRE 16 -1 (5875 1600)(5875 1550);
WIRE 16 -1 (5625 1500)(5875 1500);
WIRE 16 -1 (5875 1500)(5875 1550);
WIRE 16 -1 (5875 1450)(5625 1450);
WIRE 16 -1 (5875 1450)(5875 1500);
WIRE 16 -1 (5875 1400)(5625 1400);
WIRE 16 -1 (5875 1450)(5875 1400);
WIRE 16 -1 (5875 1350)(5625 1350);
WIRE 16 -1 (5875 1400)(5875 1350);
WIRE 16 -1 (5625 1300)(5875 1300);
WIRE 16 -1 (5875 1350)(5875 1300);
WIRE 16 -1 (5625 1250)(5875 1250);
WIRE 16 -1 (5875 1300)(5875 1250);
WIRE 16 -1 (5625 1200)(5875 1200);
WIRE 16 -1 (5875 1250)(5875 1200);
WIRE 16 -1 (5625 1150)(5875 1150);
WIRE 16 -1 (5875 1200)(5875 1150);
WIRE 16 -1 (5625 1100)(5875 1100);
WIRE 16 -1 (5875 1150)(5875 1100);
WIRE 16 -1 (5625 1050)(5875 1050);
WIRE 16 -1 (5875 1100)(5875 1050);
WIRE 16 -1 (5625 1000)(5875 1000);
WIRE 16 -1 (5875 1050)(5875 1000);
WIRE 16 -1 (5625 950)(5875 950);
WIRE 16 -1 (5875 950)(5875 1000);
WIRE 16 -1 (5625 900)(5875 900);
WIRE 16 -1 (5875 950)(5875 900);
WIRE 16 -1 (5625 800)(5875 800);
WIRE 16 -1 (5875 900)(5875 800);
WIRE 16 -1 (5875 800)(5875 750);
WIRE 16 -1 (5625 750)(5875 750);
WIRE 16 -1 (-1850 3750)(-1675 3750);
WIRE 16 -1 (-475 3300)(-300 3300);
WIRE 16 -1 (-1675 1050)(-2775 1050);
FORCEPROP 2 LAST SIG_NAME TP_CHD_CPU0_DIMM1_FRU_5
J 0
(-2687 1059);
DISPLAY 0.680851 (-2687 1059);
PAINT WHITE (-2687 1059);
WIRE 16 -1 (-1675 1100)(-2775 1100);
FORCEPROP 2 LAST SIG_NAME TP_CHD_CPU0_DIMM1_FRU_6
J 0
(-2687 1109);
DISPLAY 0.680851 (-2687 1109);
PAINT WHITE (-2687 1109);
WIRE 16 -1 (-475 1700)(-300 1700);
WIRE 16 -1 (-1675 800)(-2775 800);
FORCEPROP 2 LAST SIG_NAME TP_CHD_CPU0_DIMM1_FRU_0
J 0
(-2687 809);
DISPLAY 0.680851 (-2687 809);
PAINT WHITE (-2687 809);
WIRE 16 -1 (-1675 850)(-2775 850);
FORCEPROP 2 LAST SIG_NAME TP_CHD_CPU0_DIMM1_FRU_1
J 0
(-2687 859);
DISPLAY 0.680851 (-2687 859);
PAINT WHITE (-2687 859);
WIRE 16 -1 (-1675 900)(-2775 900);
FORCEPROP 2 LAST SIG_NAME TP_CHD_CPU0_DIMM1_FRU_2
J 0
(-2687 909);
DISPLAY 0.680851 (-2687 909);
PAINT WHITE (-2687 909);
WIRE 16 -1 (-1675 950)(-2775 950);
FORCEPROP 2 LAST SIG_NAME TP_CHD_CPU0_DIMM1_FRU_3
J 0
(-2687 959);
DISPLAY 0.680851 (-2687 959);
PAINT WHITE (-2687 959);
WIRE 16 -1 (-1675 1000)(-2775 1000);
FORCEPROP 2 LAST SIG_NAME TP_CHD_CPU0_DIMM1_FRU_4
J 0
(-2687 1009);
DISPLAY 0.680851 (-2687 1009);
PAINT WHITE (-2687 1009);
WIRE 16 -1 (-1675 3200)(-2775 3200);
FORCEPROP 2 LAST SIG_NAME M_D_CPU0_SB_PAR
J 0
(-2687 3209);
DISPLAY 0.680851 (-2687 3209);
PAINT WHITE (-2687 3209);
WIRE 16 -1 (-1675 3250)(-2775 3250);
FORCEPROP 2 LAST SIG_NAME M_D_CPU0_SA_PAR
J 0
(-2687 3259);
DISPLAY 0.680851 (-2687 3259);
PAINT WHITE (-2687 3259);
WIRE 16 -1 (-1675 600)(-2775 600);
FORCEPROP 2 LAST SIG_NAME M_D_CPU0_SB_RSP<0>
J 0
(-2687 609);
DISPLAY 0.680851 (-2687 609);
PAINT WHITE (-2687 609);
WIRE 16 -1 (-1675 650)(-2775 650);
FORCEPROP 2 LAST SIG_NAME M_D_CPU0_SA_RSP<0>
J 0
(-2687 659);
DISPLAY 0.680851 (-2687 659);
PAINT WHITE (-2687 659);
WIRE 16 -1 (-475 850)(-300 850);
WIRE 16 -1 (-475 900)(-300 900);
WIRE 16 -1 (-475 950)(-300 950);
WIRE 16 -1 (-475 1000)(-300 1000);
WIRE 16 -1 (-475 1050)(-300 1050);
WIRE 16 -1 (-475 1100)(-300 1100);
WIRE 16 -1 (-475 1150)(-300 1150);
WIRE 16 -1 (-475 1200)(-300 1200);
WIRE 16 -1 (-475 1250)(-300 1250);
WIRE 16 -1 (-475 1300)(-300 1300);
WIRE 16 -1 (-475 1350)(-300 1350);
WIRE 16 -1 (-475 1400)(-300 1400);
WIRE 16 -1 (-475 1450)(-300 1450);
WIRE 16 -1 (-475 1500)(-300 1500);
WIRE 16 -1 (-475 1550)(-300 1550);
WIRE 16 -1 (-475 1600)(-300 1600);
WIRE 16 -1 (-475 1650)(-300 1650);
WIRE 16 -1 (-475 1750)(-300 1750);
WIRE 16 -1 (-475 1800)(-300 1800);
WIRE 16 -1 (-475 1850)(-300 1850);
WIRE 16 -1 (-475 1900)(-300 1900);
WIRE 16 -1 (-475 1950)(-300 1950);
WIRE 16 -1 (-475 2000)(-300 2000);
WIRE 16 -1 (-475 2050)(-300 2050);
WIRE 16 -1 (-475 2100)(-300 2100);
WIRE 16 -1 (-475 2150)(-300 2150);
WIRE 16 -1 (-475 2200)(-300 2200);
WIRE 16 -1 (-475 2250)(-300 2250);
WIRE 16 -1 (-475 2300)(-300 2300);
WIRE 16 -1 (-475 2350)(-300 2350);
WIRE 16 -1 (-475 2400)(-300 2400);
WIRE 16 -1 (-475 2500)(-300 2500);
WIRE 16 -1 (-475 2550)(-300 2550);
WIRE 16 -1 (-475 2600)(-300 2600);
WIRE 16 -1 (-475 2650)(-300 2650);
WIRE 16 -1 (-475 2700)(-300 2700);
WIRE 16 -1 (-475 2750)(-300 2750);
WIRE 16 -1 (-475 2800)(-300 2800);
WIRE 16 -1 (-475 2850)(-300 2850);
WIRE 16 -1 (-475 2900)(-300 2900);
WIRE 16 -1 (-475 2950)(-300 2950);
WIRE 16 -1 (-475 3000)(-300 3000);
WIRE 16 -1 (-475 3050)(-300 3050);
WIRE 16 -1 (-475 3100)(-300 3100);
WIRE 16 -1 (-475 3150)(-300 3150);
WIRE 16 -1 (-475 3200)(-300 3200);
WIRE 16 -1 (-475 3250)(-300 3250);
WIRE 16 -1 (-475 3350)(-300 3350);
WIRE 16 -1 (-475 3400)(-300 3400);
WIRE 16 -1 (-475 3450)(-300 3450);
WIRE 16 -1 (-475 3500)(-300 3500);
WIRE 16 -1 (-475 3550)(-300 3550);
WIRE 16 -1 (-475 3600)(-300 3600);
WIRE 16 -1 (-475 3650)(-300 3650);
WIRE 16 -1 (-475 3700)(-300 3700);
WIRE 16 -1 (-475 3750)(-300 3750);
WIRE 16 -1 (-475 3850)(-300 3850);
WIRE 16 -1 (-1675 2950)(-2775 2950);
FORCEPROP 2 LAST SIG_NAME M_D_CPU0_SB_CS_N<1>
J 0
(-2687 2959);
DISPLAY 0.680851 (-2687 2959);
PAINT WHITE (-2687 2959);
WIRE 16 -1 (-1675 3100)(-2775 3100);
FORCEPROP 2 LAST SIG_NAME M_D_CPU0_SA_CS_N<1>
J 0
(-2687 3109);
DISPLAY 0.680851 (-2687 3109);
PAINT WHITE (-2687 3109);
WIRE 16 -1 (-1675 2900)(-2775 2900);
FORCEPROP 2 LAST SIG_NAME M_D_CPU0_SB_CS_N<0>
J 0
(-2687 2909);
DISPLAY 0.680851 (-2687 2909);
PAINT WHITE (-2687 2909);
WIRE 16 -1 (-1675 3050)(-2775 3050);
FORCEPROP 2 LAST SIG_NAME M_D_CPU0_SA_CS_N<0>
J 0
(-2687 3059);
DISPLAY 0.680851 (-2687 3059);
PAINT WHITE (-2687 3059);
WIRE 16 -1 (-1675 2800)(-2775 2800);
FORCEPROP 2 LAST SIG_NAME M_D_CPU0_CLK_DP<0>
J 0
(-2687 2809);
DISPLAY 0.680851 (-2687 2809);
PAINT WHITE (-2687 2809);
WIRE 16 -1 (-1675 2750)(-2775 2750);
FORCEPROP 2 LAST SIG_NAME M_D_CPU0_CLK_DN<0>
J 0
(-2687 2759);
DISPLAY 0.680851 (-2687 2759);
PAINT WHITE (-2687 2759);
WIRE 16 -1 (-1850 1900)(-1675 1900);
WIRE 16 -1 (-1850 1950)(-1675 1950);
WIRE 16 -1 (-1850 2000)(-1675 2000);
WIRE 16 -1 (-1850 2050)(-1675 2050);
WIRE 16 -1 (-1850 2100)(-1675 2100);
WIRE 16 -1 (-1850 2150)(-1675 2150);
WIRE 16 -1 (-1850 2300)(-1675 2300);
WIRE 16 -1 (-1850 2400)(-1675 2400);
WIRE 16 -1 (-1850 2450)(-1675 2450);
WIRE 16 -1 (-1850 2550)(-1675 2550);
WIRE 16 -1 (-1850 2600)(-1675 2600);
WIRE 16 -1 (-1850 3650)(-1675 3650);
WIRE 16 -1 (-1850 4050)(-1675 4050);
WIRE 16 -1 (-1850 3600)(-1675 3600);
WIRE 16 -1 (-1850 4000)(-1675 4000);
WIRE 16 -1 (-1850 3550)(-1675 3550);
WIRE 16 -1 (-1850 3950)(-1675 3950);
WIRE 16 -1 (-1850 3500)(-1675 3500);
WIRE 16 -1 (-1850 3900)(-1675 3900);
WIRE 16 -1 (-1850 3450)(-1675 3450);
WIRE 16 -1 (-1850 3850)(-1675 3850);
WIRE 16 -1 (-1850 3400)(-1675 3400);
WIRE 16 -1 (-1850 3800)(-1675 3800);
WIRE 16 -1 (-1850 3350)(-1675 3350);
WIRE 16 -1 (-1850 2200)(-1675 2200);
WIRE 16 -1 (-1850 2350)(-1675 2350);
WIRE 16 -1 (-1850 2500)(-1675 2500);
WIRE 16 -1 (-1850 2650)(-1675 2650);
WIRE 16 -1 (-475 4050)(-300 4050);
WIRE 16 -1 (-1675 0)(-1675 100);
WIRE 16 -1 (-1675 100)(-2775 100);
FORCEPROP 2 LAST SIG_NAME PD_CHD_CPU0_DIMM1_SAA
J 0
(-2687 109);
DISPLAY 0.680851 (-2687 109);
PAINT WHITE (-2687 109);
DOT 1 (5875 700);
DOT 1 (5875 750);
DOT 1 (5875 800);
DOT 1 (3100 -75);
DOT 1 (2475 400);
DOT 1 (4175 850);
DOT 1 (4175 800);
DOT 1 (4175 900);
DOT 1 (4175 950);
DOT 1 (4175 1000);
DOT 1 (4175 1050);
DOT 1 (4175 1100);
DOT 1 (4175 1150);
DOT 1 (4175 1200);
DOT 1 (4175 1300);
DOT 1 (4175 1350);
DOT 1 (4175 1400);
DOT 1 (4175 1500);
DOT 1 (4175 1450);
DOT 1 (4175 1550);
DOT 1 (4175 1600);
DOT 1 (4175 1700);
DOT 1 (4175 1800);
DOT 1 (4175 1850);
DOT 1 (4175 1900);
DOT 1 (4175 1950);
DOT 1 (4175 2000);
DOT 1 (5875 900);
DOT 1 (5875 1000);
DOT 1 (5875 950);
DOT 1 (5875 1150);
DOT 1 (5875 1100);
DOT 1 (5875 1050);
DOT 1 (5875 1200);
DOT 1 (5875 1250);
DOT 1 (5875 1350);
DOT 1 (5875 1400);
DOT 1 (5875 1300);
DOT 1 (5875 1500);
DOT 1 (5875 1450);
DOT 1 (5875 1550);
DOT 1 (5875 1600);
DOT 1 (5875 1650);
DOT 1 (5875 1700);
DOT 1 (5875 1750);
DOT 1 (5875 1800);
DOT 1 (5875 1900);
DOT 1 (5875 1850);
DOT 1 (5875 1950);
DOT 1 (5875 2000);
DOT 1 (4175 2050);
DOT 1 (5875 2050);
DOT 1 (4175 2100);
DOT 1 (4175 2150);
DOT 1 (4175 2200);
DOT 1 (4175 2250);
DOT 1 (4175 2300);
DOT 1 (4175 2350);
DOT 1 (4175 2400);
DOT 1 (4175 2450);
DOT 1 (4175 2500);
DOT 1 (4175 2550);
DOT 1 (4175 2600);
DOT 1 (4175 2650);
DOT 1 (4175 2700);
DOT 1 (4175 2750);
DOT 1 (4175 2800);
DOT 1 (4175 2850);
DOT 1 (4175 2900);
DOT 1 (4175 2950);
DOT 1 (4175 3000);
DOT 1 (4175 3050);
DOT 1 (4175 3100);
DOT 1 (4175 3150);
DOT 1 (4175 3200);
DOT 1 (4175 3250);
DOT 1 (4175 3300);
DOT 1 (4175 3350);
DOT 1 (4175 3400);
DOT 1 (4175 3450);
DOT 1 (4175 3500);
DOT 1 (4175 3550);
DOT 1 (4175 3600);
DOT 1 (4175 3650);
DOT 1 (4175 3700);
DOT 1 (4175 3750);
DOT 1 (4175 3800);
DOT 1 (4175 3850);
DOT 1 (4175 4000);
DOT 1 (4175 4050);
DOT 1 (5875 2150);
DOT 1 (5875 2100);
DOT 1 (5875 2300);
DOT 1 (5875 2250);
DOT 1 (5875 2200);
DOT 1 (5875 2350);
DOT 1 (5875 2400);
DOT 1 (5875 2500);
DOT 1 (5875 2550);
DOT 1 (5875 2450);
DOT 1 (5875 2650);
DOT 1 (5875 2600);
DOT 1 (5875 2700);
DOT 1 (5875 2800);
DOT 1 (5875 2750);
DOT 1 (5875 2850);
DOT 1 (5875 2900);
DOT 1 (5875 2950);
DOT 1 (5875 3050);
DOT 1 (5875 3000);
DOT 1 (5875 3100);
DOT 1 (5875 3150);
DOT 1 (5875 3200);
DOT 1 (5875 3250);
DOT 1 (5875 3300);
DOT 1 (5875 3400);
DOT 1 (5875 3450);
DOT 1 (5875 3350);
DOT 1 (5875 3500);
DOT 1 (5875 3550);
DOT 1 (5875 3700);
DOT 1 (5875 3650);
DOT 1 (5875 3600);
DOT 1 (5875 3750);
DOT 1 (5875 3800);
DOT 1 (5875 3850);
DOT 1 (5875 3950);
DOT 1 (5875 3900);
DOT 1 (5875 4000);
DOT 1 (4175 1650);
DOT 1 (4175 1750);
DOT 1 (4175 1250);
FORCENOTE
20210728 MODIFY FOR GT
(-3175 4725) 0;
DISPLAY LEFT (-3175 4725);
DISPLAY 2.510638 (-3175 4725);
PAINT PINK (-3175 4725);
QUIT
